G04 ================== begin FILE IDENTIFICATION RECORD ==================*
G04 Layout Name:  D:/<user>/Wistron_project/16315-1/gbr/16315-1.brd*
G04 Film Name:    L12*
G04 File Format:  Gerber RS274X*
G04 File Origin:  Cadence Allegro 16.5-S056*
G04 Origin Date:  Fri Jun 09 15:32:17 2017*
G04 *
G04 Layer:  VIA CLASS/BOTTOM*
G04 Layer:  PIN/BOTTOM*
G04 Layer:  ETCH/BOTTOM*
G04 Layer:  DRAWING FORMAT/LAYER_PCB_STORY*
G04 Layer:  DRAWING FORMAT/LAYER_L12*
G04 *
G04 Offset:    (0.00 0.00)*
G04 Mirror:    No*
G04 Mode:      Positive*
G04 Rotation:  0*
G04 FullContactRelief:  No*
G04 UndefLineWidth:     6.00*
G04 ================== end FILE IDENTIFICATION RECORD ====================*
%FSLAX35Y35*MOIN*%
%IR0*IPPOS*OFA0.00000B0.00000*MIA0B0*SFA1.00000B1.00000*%
%AMMACRO49*
4,1,40,.011,.007,
.011,-.007,
.010939,-.007695,
.010759,-.008368,
.010464,-.009,
.010064,-.009571,
.009571,-.010064,
.009,-.010464,
.008368,-.010759,
.007695,-.010939,
.007,-.011,
-.007,-.011,
-.007695,-.010939,
-.008368,-.010759,
-.009,-.010464,
-.009571,-.010064,
-.010064,-.009571,
-.010464,-.009,
-.010759,-.008368,
-.010939,-.007695,
-.011,-.007,
-.011,.007,
-.010939,.007695,
-.010759,.008368,
-.010464,.009,
-.010064,.009571,
-.009571,.010064,
-.009,.010464,
-.008368,.010759,
-.007695,.010939,
-.007,.011,
.007,.011,
.007695,.010939,
.008368,.010759,
.009,.010464,
.009571,.010064,
.010064,.009571,
.010464,.009,
.010759,.008368,
.010939,.007695,
.011,.007,
0.0*
%
%ADD49MACRO49*%
%AMMACRO38*
4,1,40,.013,-.017,
-.013,-.017,
-.013695,-.016939,
-.014368,-.016759,
-.015,-.016464,
-.015571,-.016064,
-.016064,-.015571,
-.016464,-.015,
-.016759,-.014368,
-.016939,-.013695,
-.017,-.013,
-.017,.013,
-.016939,.013695,
-.016759,.014368,
-.016464,.015,
-.016064,.015571,
-.015571,.016064,
-.015,.016464,
-.014368,.016759,
-.013695,.016939,
-.013,.017,
.013,.017,
.013695,.016939,
.014368,.016759,
.015,.016464,
.015571,.016064,
.016064,.015571,
.016464,.015,
.016759,.014368,
.016939,.013695,
.017,.013,
.017,-.013,
.016939,-.013695,
.016759,-.014368,
.016464,-.015,
.016064,-.015571,
.015571,-.016064,
.015,-.016464,
.014368,-.016759,
.013695,-.016939,
.013,-.017,
0.0*
%
%ADD38MACRO38*%
%AMMACRO18*
4,1,40,-.017,-.013,
-.017,.013,
-.016939,.013695,
-.016759,.014368,
-.016464,.015,
-.016064,.015571,
-.015571,.016064,
-.015,.016464,
-.014368,.016759,
-.013695,.016939,
-.013,.017,
.013,.017,
.013695,.016939,
.014368,.016759,
.015,.016464,
.015571,.016064,
.016064,.015571,
.016464,.015,
.016759,.014368,
.016939,.013695,
.017,.013,
.017,-.013,
.016939,-.013695,
.016759,-.014368,
.016464,-.015,
.016064,-.015571,
.015571,-.016064,
.015,-.016464,
.014368,-.016759,
.013695,-.016939,
.013,-.017,
-.013,-.017,
-.013695,-.016939,
-.014368,-.016759,
-.015,-.016464,
-.015571,-.016064,
-.016064,-.015571,
-.016464,-.015,
-.016759,-.014368,
-.016939,-.013695,
-.017,-.013,
0.0*
%
%ADD18MACRO18*%
%ADD44R,.01X.007*%
%ADD63R,.007X.01*%
%ADD15C,.01*%
%ADD33C,.02*%
%ADD45C,.03*%
%ADD74R,.08X.127*%
%ADD14C,.04*%
%ADD12C,.022*%
%ADD59C,.032*%
%ADD47R,.127X.08*%
%ADD71C,.042*%
%ADD32C,.024*%
%ADD73C,.034*%
%ADD46C,.026*%
%ADD11C,.028*%
%ADD72C,.048*%
%ADD52R,.066X.066*%
%AMMACRO50*
4,1,40,.007,-.011,
-.007,-.011,
-.007695,-.010939,
-.008368,-.010759,
-.009,-.010464,
-.009571,-.010064,
-.010064,-.009571,
-.010464,-.009,
-.010759,-.008368,
-.010939,-.007695,
-.011,-.007,
-.011,.007,
-.010939,.007695,
-.010759,.008368,
-.010464,.009,
-.010064,.009571,
-.009571,.010064,
-.009,.010464,
-.008368,.010759,
-.007695,.010939,
-.007,.011,
.007,.011,
.007695,.010939,
.008368,.010759,
.009,.010464,
.009571,.010064,
.010064,.009571,
.010464,.009,
.010759,.008368,
.010939,.007695,
.011,.007,
.011,-.007,
.010939,-.007695,
.010759,-.008368,
.010464,-.009,
.010064,-.009571,
.009571,-.010064,
.009,-.010464,
.008368,-.010759,
.007695,-.010939,
.007,-.011,
0.0*
%
%ADD50MACRO50*%
%AMMACRO28*
4,1,40,-.011,-.007,
-.011,.007,
-.010939,.007695,
-.010759,.008368,
-.010464,.009,
-.010064,.009571,
-.009571,.010064,
-.009,.010464,
-.008368,.010759,
-.007695,.010939,
-.007,.011,
.007,.011,
.007695,.010939,
.008368,.010759,
.009,.010464,
.009571,.010064,
.010064,.009571,
.010464,.009,
.010759,.008368,
.010939,.007695,
.011,.007,
.011,-.007,
.010939,-.007695,
.010759,-.008368,
.010464,-.009,
.010064,-.009571,
.009571,-.010064,
.009,-.010464,
.008368,-.010759,
.007695,-.010939,
.007,-.011,
-.007,-.011,
-.007695,-.010939,
-.008368,-.010759,
-.009,-.010464,
-.009571,-.010064,
-.010064,-.009571,
-.010464,-.009,
-.010759,-.008368,
-.010939,-.007695,
-.011,-.007,
0.0*
%
%ADD28MACRO28*%
%AMMACRO40*
4,1,40,-.012,-.008,
-.012,.008,
-.011939,.008695,
-.011759,.009368,
-.011464,.01,
-.011064,.010571,
-.010571,.011064,
-.01,.011464,
-.009368,.011759,
-.008695,.011939,
-.008,.012,
.008,.012,
.008695,.011939,
.009368,.011759,
.01,.011464,
.010571,.011064,
.011064,.010571,
.011464,.01,
.011759,.009368,
.011939,.008695,
.012,.008,
.012,-.008,
.011939,-.008695,
.011759,-.009368,
.011464,-.01,
.011064,-.010571,
.010571,-.011064,
.01,-.011464,
.009368,-.011759,
.008695,-.011939,
.008,-.012,
-.008,-.012,
-.008695,-.011939,
-.009368,-.011759,
-.01,-.011464,
-.010571,-.011064,
-.011064,-.010571,
-.011464,-.01,
-.011759,-.009368,
-.011939,-.008695,
-.012,-.008,
0.0*
%
%ADD40MACRO40*%
%AMMACRO68*
4,1,40,-.008,.012,
.008,.012,
.008695,.011939,
.009368,.011759,
.01,.011464,
.010571,.011064,
.011064,.010571,
.011464,.01,
.011759,.009368,
.011939,.008695,
.012,.008,
.012,-.008,
.011939,-.008695,
.011759,-.009368,
.011464,-.01,
.011064,-.010571,
.010571,-.011064,
.01,-.011464,
.009368,-.011759,
.008695,-.011939,
.008,-.012,
-.008,-.012,
-.008695,-.011939,
-.009368,-.011759,
-.01,-.011464,
-.010571,-.011064,
-.011064,-.010571,
-.011464,-.01,
-.011759,-.009368,
-.011939,-.008695,
-.012,-.008,
-.012,.008,
-.011939,.008695,
-.011759,.009368,
-.011464,.01,
-.011064,.010571,
-.010571,.011064,
-.01,.011464,
-.009368,.011759,
-.008695,.011939,
-.008,.012,
0.0*
%
%ADD68MACRO68*%
%AMMACRO24*
4,1,40,-.013,.017,
.013,.017,
.013695,.016939,
.014368,.016759,
.015,.016464,
.015571,.016064,
.016064,.015571,
.016464,.015,
.016759,.014368,
.016939,.013695,
.017,.013,
.017,-.013,
.016939,-.013695,
.016759,-.014368,
.016464,-.015,
.016064,-.015571,
.015571,-.016064,
.015,-.016464,
.014368,-.016759,
.013695,-.016939,
.013,-.017,
-.013,-.017,
-.013695,-.016939,
-.014368,-.016759,
-.015,-.016464,
-.015571,-.016064,
-.016064,-.015571,
-.016464,-.015,
-.016759,-.014368,
-.016939,-.013695,
-.017,-.013,
-.017,.013,
-.016939,.013695,
-.016759,.014368,
-.016464,.015,
-.016064,.015571,
-.015571,.016064,
-.015,.016464,
-.014368,.016759,
-.013695,.016939,
-.013,.017,
0.0*
%
%ADD24MACRO24*%
%AMMACRO60*
4,1,40,.017,.013,
.017,-.013,
.016939,-.013695,
.016759,-.014368,
.016464,-.015,
.016064,-.015571,
.015571,-.016064,
.015,-.016464,
.014368,-.016759,
.013695,-.016939,
.013,-.017,
-.013,-.017,
-.013695,-.016939,
-.014368,-.016759,
-.015,-.016464,
-.015571,-.016064,
-.016064,-.015571,
-.016464,-.015,
-.016759,-.014368,
-.016939,-.013695,
-.017,-.013,
-.017,.013,
-.016939,.013695,
-.016759,.014368,
-.016464,.015,
-.016064,.015571,
-.015571,.016064,
-.015,.016464,
-.014368,.016759,
-.013695,.016939,
-.013,.017,
.013,.017,
.013695,.016939,
.014368,.016759,
.015,.016464,
.015571,.016064,
.016064,.015571,
.016464,.015,
.016759,.014368,
.016939,.013695,
.017,.013,
0.0*
%
%ADD60MACRO60*%
%AMMACRO31*
4,1,6,.025,-.0135,
.005,.0065,
.005,.0135,
-.005,.0135,
-.005,.0065,
-.025,-.0135,
.025,-.0135,
0.0*
%
%ADD31MACRO31*%
%AMMACRO57*
4,1,6,-.0135,-.005,
-.0065,-.005,
.0135,-.025,
.0135,.025,
-.0065,.005,
-.0135,.005,
-.0135,-.005,
0.0*
%
%ADD57MACRO57*%
%AMMACRO51*
4,1,40,.007,-.011,
-.007,-.011,
-.007695,-.010939,
-.008368,-.010759,
-.009,-.010464,
-.009571,-.010064,
-.010064,-.009571,
-.010464,-.009,
-.010759,-.008368,
-.010939,-.007695,
-.011,-.007,
-.011,.007,
-.010939,.007695,
-.010759,.008368,
-.010464,.009,
-.010064,.009571,
-.009571,.010064,
-.009,.010464,
-.008368,.010759,
-.007695,.010939,
-.007,.011,
.007,.011,
.007695,.010939,
.008368,.010759,
.009,.010464,
.009571,.010064,
.010064,.009571,
.010464,.009,
.010759,.008368,
.010939,.007695,
.011,.007,
.011,-.007,
.010939,-.007695,
.010759,-.008368,
.010464,-.009,
.010064,-.009571,
.009571,-.010064,
.009,-.010464,
.008368,-.010759,
.007695,-.010939,
.007,-.011,
0.0*
%
%ADD51MACRO51*%
%AMMACRO29*
4,1,40,-.011,-.007,
-.011,.007,
-.010939,.007695,
-.010759,.008368,
-.010464,.009,
-.010064,.009571,
-.009571,.010064,
-.009,.010464,
-.008368,.010759,
-.007695,.010939,
-.007,.011,
.007,.011,
.007695,.010939,
.008368,.010759,
.009,.010464,
.009571,.010064,
.010064,.009571,
.010464,.009,
.010759,.008368,
.010939,.007695,
.011,.007,
.011,-.007,
.010939,-.007695,
.010759,-.008368,
.010464,-.009,
.010064,-.009571,
.009571,-.010064,
.009,-.010464,
.008368,-.010759,
.007695,-.010939,
.007,-.011,
-.007,-.011,
-.007695,-.010939,
-.008368,-.010759,
-.009,-.010464,
-.009571,-.010064,
-.010064,-.009571,
-.010464,-.009,
-.010759,-.008368,
-.010939,-.007695,
-.011,-.007,
0.0*
%
%ADD29MACRO29*%
%AMMACRO39*
4,1,40,-.012,-.008,
-.012,.008,
-.011939,.008695,
-.011759,.009368,
-.011464,.01,
-.011064,.010571,
-.010571,.011064,
-.01,.011464,
-.009368,.011759,
-.008695,.011939,
-.008,.012,
.008,.012,
.008695,.011939,
.009368,.011759,
.01,.011464,
.010571,.011064,
.011064,.010571,
.011464,.01,
.011759,.009368,
.011939,.008695,
.012,.008,
.012,-.008,
.011939,-.008695,
.011759,-.009368,
.011464,-.01,
.011064,-.010571,
.010571,-.011064,
.01,-.011464,
.009368,-.011759,
.008695,-.011939,
.008,-.012,
-.008,-.012,
-.008695,-.011939,
-.009368,-.011759,
-.01,-.011464,
-.010571,-.011064,
-.011064,-.010571,
-.011464,-.01,
-.011759,-.009368,
-.011939,-.008695,
-.012,-.008,
0.0*
%
%ADD39MACRO39*%
%AMMACRO67*
4,1,40,-.008,.012,
.008,.012,
.008695,.011939,
.009368,.011759,
.01,.011464,
.010571,.011064,
.011064,.010571,
.011464,.01,
.011759,.009368,
.011939,.008695,
.012,.008,
.012,-.008,
.011939,-.008695,
.011759,-.009368,
.011464,-.01,
.011064,-.010571,
.010571,-.011064,
.01,-.011464,
.009368,-.011759,
.008695,-.011939,
.008,-.012,
-.008,-.012,
-.008695,-.011939,
-.009368,-.011759,
-.01,-.011464,
-.010571,-.011064,
-.011064,-.010571,
-.011464,-.01,
-.011759,-.009368,
-.011939,-.008695,
-.012,-.008,
-.012,.008,
-.011939,.008695,
-.011759,.009368,
-.011464,.01,
-.011064,.010571,
-.010571,.011064,
-.01,.011464,
-.009368,.011759,
-.008695,.011939,
-.008,.012,
0.0*
%
%ADD67MACRO67*%
%AMMACRO25*
4,1,40,-.013,.017,
.013,.017,
.013695,.016939,
.014368,.016759,
.015,.016464,
.015571,.016064,
.016064,.015571,
.016464,.015,
.016759,.014368,
.016939,.013695,
.017,.013,
.017,-.013,
.016939,-.013695,
.016759,-.014368,
.016464,-.015,
.016064,-.015571,
.015571,-.016064,
.015,-.016464,
.014368,-.016759,
.013695,-.016939,
.013,-.017,
-.013,-.017,
-.013695,-.016939,
-.014368,-.016759,
-.015,-.016464,
-.015571,-.016064,
-.016064,-.015571,
-.016464,-.015,
-.016759,-.014368,
-.016939,-.013695,
-.017,-.013,
-.017,.013,
-.016939,.013695,
-.016759,.014368,
-.016464,.015,
-.016064,.015571,
-.015571,.016064,
-.015,.016464,
-.014368,.016759,
-.013695,.016939,
-.013,.017,
0.0*
%
%ADD25MACRO25*%
%AMMACRO61*
4,1,40,.017,.013,
.017,-.013,
.016939,-.013695,
.016759,-.014368,
.016464,-.015,
.016064,-.015571,
.015571,-.016064,
.015,-.016464,
.014368,-.016759,
.013695,-.016939,
.013,-.017,
-.013,-.017,
-.013695,-.016939,
-.014368,-.016759,
-.015,-.016464,
-.015571,-.016064,
-.016064,-.015571,
-.016464,-.015,
-.016759,-.014368,
-.016939,-.013695,
-.017,-.013,
-.017,.013,
-.016939,.013695,
-.016759,.014368,
-.016464,.015,
-.016064,.015571,
-.015571,.016064,
-.015,.016464,
-.014368,.016759,
-.013695,.016939,
-.013,.017,
.013,.017,
.013695,.016939,
.014368,.016759,
.015,.016464,
.015571,.016064,
.016064,.015571,
.016464,.015,
.016759,.014368,
.016939,.013695,
.017,.013,
0.0*
%
%ADD61MACRO61*%
%ADD69R,.06X.012*%
%ADD22R,.044X.012*%
%ADD77R,.012X.044*%
%ADD34R,.14X.138*%
%ADD75R,.138X.14*%
%ADD55R,.012X.036*%
%ADD53R,.036X.012*%
%ADD56R,.012X.037*%
%ADD54R,.037X.012*%
%ADD62R,.138X.115*%
%ADD64R,.065X.05*%
%ADD23R,.045X.055*%
%ADD16R,.055X.045*%
%ADD13C,.256*%
%ADD66R,.09X.095*%
%ADD65R,.057X.083*%
%ADD43R,.095X.09*%
%ADD19C,.375*%
%ADD10C,.296*%
%ADD20O,.552X.788*%
%AMMACRO42*
4,1,40,.012,.008,
.012,-.008,
.011939,-.008695,
.011759,-.009368,
.011464,-.01,
.011064,-.010571,
.010571,-.011064,
.01,-.011464,
.009368,-.011759,
.008695,-.011939,
.008,-.012,
-.008,-.012,
-.008695,-.011939,
-.009368,-.011759,
-.01,-.011464,
-.010571,-.011064,
-.011064,-.010571,
-.011464,-.01,
-.011759,-.009368,
-.011939,-.008695,
-.012,-.008,
-.012,.008,
-.011939,.008695,
-.011759,.009368,
-.011464,.01,
-.011064,.010571,
-.010571,.011064,
-.01,.011464,
-.009368,.011759,
-.008695,.011939,
-.008,.012,
.008,.012,
.008695,.011939,
.009368,.011759,
.01,.011464,
.010571,.011064,
.011064,.010571,
.011464,.01,
.011759,.009368,
.011939,.008695,
.012,.008,
0.0*
%
%ADD42MACRO42*%
%AMMACRO35*
4,1,40,-.007,.011,
.007,.011,
.007695,.010939,
.008368,.010759,
.009,.010464,
.009571,.010064,
.010064,.009571,
.010464,.009,
.010759,.008368,
.010939,.007695,
.011,.007,
.011,-.007,
.010939,-.007695,
.010759,-.008368,
.010464,-.009,
.010064,-.009571,
.009571,-.010064,
.009,-.010464,
.008368,-.010759,
.007695,-.010939,
.007,-.011,
-.007,-.011,
-.007695,-.010939,
-.008368,-.010759,
-.009,-.010464,
-.009571,-.010064,
-.010064,-.009571,
-.010464,-.009,
-.010759,-.008368,
-.010939,-.007695,
-.011,-.007,
-.011,.007,
-.010939,.007695,
-.010759,.008368,
-.010464,.009,
-.010064,.009571,
-.009571,.010064,
-.009,.010464,
-.008368,.010759,
-.007695,.010939,
-.007,.011,
0.0*
%
%ADD35MACRO35*%
%AMMACRO27*
4,1,40,.008,-.012,
-.008,-.012,
-.008695,-.011939,
-.009368,-.011759,
-.01,-.011464,
-.010571,-.011064,
-.011064,-.010571,
-.011464,-.01,
-.011759,-.009368,
-.011939,-.008695,
-.012,-.008,
-.012,.008,
-.011939,.008695,
-.011759,.009368,
-.011464,.01,
-.011064,.010571,
-.010571,.011064,
-.01,.011464,
-.009368,.011759,
-.008695,.011939,
-.008,.012,
.008,.012,
.008695,.011939,
.009368,.011759,
.01,.011464,
.010571,.011064,
.011064,.010571,
.011464,.01,
.011759,.009368,
.011939,.008695,
.012,.008,
.012,-.008,
.011939,-.008695,
.011759,-.009368,
.011464,-.01,
.011064,-.010571,
.010571,-.011064,
.01,-.011464,
.009368,-.011759,
.008695,-.011939,
.008,-.012,
0.0*
%
%ADD27MACRO27*%
%AMMACRO70*
4,1,45,.25591,.11811,
.25591,-.11811,
.252022,-.162547,
.240477,-.205635,
.221625,-.246062,
.19604,-.282603,
.164498,-.314145,
.127958,-.33973,
.08753,-.358582,
.044442,-.370127,
.000005,-.374015,
-.044432,-.370127,
-.08752,-.358582,
-.127947,-.33973,
-.164488,-.314145,
-.19603,-.282603,
-.221615,-.246063,
-.240467,-.205635,
-.252012,-.162547,
-.2559,-.11811,
-.2559,.11811,
-.252012,.162547,
-.240467,.205634,
-.221616,.246061,
-.19603,.282601,
-.164488,.314143,
-.127949,.339728,
-.087521,.35858,
-.044434,.370125,
.000003,.374013,
.04444,.370125,
.087526,.35858,
.127954,.339728,
.16179,.31638,
.165832,.290964,
.174225,.266637,
.186715,.244136,
.202923,.224146,
.222356,.207275,
.24439,.19405,
.248391,.17971,
.251551,.165162,
.25386,.150455,
.25531,.135639,
.255896,.120763,
.25591,.11811,
0.0*
%
%ADD70MACRO70*%
%AMMACRO48*
4,1,40,.011,.007,
.011,-.007,
.010939,-.007695,
.010759,-.008368,
.010464,-.009,
.010064,-.009571,
.009571,-.010064,
.009,-.010464,
.008368,-.010759,
.007695,-.010939,
.007,-.011,
-.007,-.011,
-.007695,-.010939,
-.008368,-.010759,
-.009,-.010464,
-.009571,-.010064,
-.010064,-.009571,
-.010464,-.009,
-.010759,-.008368,
-.010939,-.007695,
-.011,-.007,
-.011,.007,
-.010939,.007695,
-.010759,.008368,
-.010464,.009,
-.010064,.009571,
-.009571,.010064,
-.009,.010464,
-.008368,.010759,
-.007695,.010939,
-.007,.011,
.007,.011,
.007695,.010939,
.008368,.010759,
.009,.010464,
.009571,.010064,
.010064,.009571,
.010464,.009,
.010759,.008368,
.010939,.007695,
.011,.007,
0.0*
%
%ADD48MACRO48*%
%AMMACRO58*
4,1,6,-.0135,-.025,
.0065,-.005,
.0135,-.005,
.0135,.005,
.0065,.005,
-.0135,.025,
-.0135,-.025,
0.0*
%
%ADD58MACRO58*%
%AMMACRO37*
4,1,40,.013,-.017,
-.013,-.017,
-.013695,-.016939,
-.014368,-.016759,
-.015,-.016464,
-.015571,-.016064,
-.016064,-.015571,
-.016464,-.015,
-.016759,-.014368,
-.016939,-.013695,
-.017,-.013,
-.017,.013,
-.016939,.013695,
-.016759,.014368,
-.016464,.015,
-.016064,.015571,
-.015571,.016064,
-.015,.016464,
-.014368,.016759,
-.013695,.016939,
-.013,.017,
.013,.017,
.013695,.016939,
.014368,.016759,
.015,.016464,
.015571,.016064,
.016064,.015571,
.016464,.015,
.016759,.014368,
.016939,.013695,
.017,.013,
.017,-.013,
.016939,-.013695,
.016759,-.014368,
.016464,-.015,
.016064,-.015571,
.015571,-.016064,
.015,-.016464,
.014368,-.016759,
.013695,-.016939,
.013,-.017,
0.0*
%
%ADD37MACRO37*%
%AMMACRO17*
4,1,40,-.017,-.013,
-.017,.013,
-.016939,.013695,
-.016759,.014368,
-.016464,.015,
-.016064,.015571,
-.015571,.016064,
-.015,.016464,
-.014368,.016759,
-.013695,.016939,
-.013,.017,
.013,.017,
.013695,.016939,
.014368,.016759,
.015,.016464,
.015571,.016064,
.016064,.015571,
.016464,.015,
.016759,.014368,
.016939,.013695,
.017,.013,
.017,-.013,
.016939,-.013695,
.016759,-.014368,
.016464,-.015,
.016064,-.015571,
.015571,-.016064,
.015,-.016464,
.014368,-.016759,
.013695,-.016939,
.013,-.017,
-.013,-.017,
-.013695,-.016939,
-.014368,-.016759,
-.015,-.016464,
-.015571,-.016064,
-.016064,-.015571,
-.016464,-.015,
-.016759,-.014368,
-.016939,-.013695,
-.017,-.013,
0.0*
%
%ADD17MACRO17*%
%AMMACRO76*
4,1,20,-.1095,.0655,
-.1095,.051,
-.12,.051,
-.12,.0375,
-.1095,.0375,
-.1095,-.0375,
-.12,-.0375,
-.12,-.051,
-.1095,-.051,
-.1095,-.0655,
.1095,-.0655,
.1095,-.051,
.12,-.051,
.12,-.0375,
.1095,-.0375,
.1095,.0375,
.12,.0375,
.12,.051,
.1095,.051,
.1095,.0655,
-.1095,.0655,
0.0*
%
%ADD76MACRO76*%
%AMMACRO21*
4,1,20,-.0655,-.1095,
-.051,-.1095,
-.051,-.12,
-.0375,-.12,
-.0375,-.1095,
.0375,-.1095,
.0375,-.12,
.051,-.12,
.051,-.1095,
.0655,-.1095,
.0655,.1095,
.051,.1095,
.051,.12,
.0375,.12,
.0375,.1095,
-.0375,.1095,
-.0375,.12,
-.051,.12,
-.051,.1095,
-.0655,.1095,
-.0655,-.1095,
0.0*
%
%ADD21MACRO21*%
%AMMACRO30*
4,1,6,.005,-.0135,
.005,-.0065,
.025,.0135,
-.025,.0135,
-.005,-.0065,
-.005,-.0135,
.005,-.0135,
0.0*
%
%ADD30MACRO30*%
%AMMACRO41*
4,1,40,.012,.008,
.012,-.008,
.011939,-.008695,
.011759,-.009368,
.011464,-.01,
.011064,-.010571,
.010571,-.011064,
.01,-.011464,
.009368,-.011759,
.008695,-.011939,
.008,-.012,
-.008,-.012,
-.008695,-.011939,
-.009368,-.011759,
-.01,-.011464,
-.010571,-.011064,
-.011064,-.010571,
-.011464,-.01,
-.011759,-.009368,
-.011939,-.008695,
-.012,-.008,
-.012,.008,
-.011939,.008695,
-.011759,.009368,
-.011464,.01,
-.011064,.010571,
-.010571,.011064,
-.01,.011464,
-.009368,.011759,
-.008695,.011939,
-.008,.012,
.008,.012,
.008695,.011939,
.009368,.011759,
.01,.011464,
.010571,.011064,
.011064,.010571,
.011464,.01,
.011759,.009368,
.011939,.008695,
.012,.008,
0.0*
%
%ADD41MACRO41*%
%AMMACRO36*
4,1,40,-.007,.011,
.007,.011,
.007695,.010939,
.008368,.010759,
.009,.010464,
.009571,.010064,
.010064,.009571,
.010464,.009,
.010759,.008368,
.010939,.007695,
.011,.007,
.011,-.007,
.010939,-.007695,
.010759,-.008368,
.010464,-.009,
.010064,-.009571,
.009571,-.010064,
.009,-.010464,
.008368,-.010759,
.007695,-.010939,
.007,-.011,
-.007,-.011,
-.007695,-.010939,
-.008368,-.010759,
-.009,-.010464,
-.009571,-.010064,
-.010064,-.009571,
-.010464,-.009,
-.010759,-.008368,
-.010939,-.007695,
-.011,-.007,
-.011,.007,
-.010939,.007695,
-.010759,.008368,
-.010464,.009,
-.010064,.009571,
-.009571,.010064,
-.009,.010464,
-.008368,.010759,
-.007695,.010939,
-.007,.011,
0.0*
%
%ADD36MACRO36*%
%AMMACRO26*
4,1,40,.008,-.012,
-.008,-.012,
-.008695,-.011939,
-.009368,-.011759,
-.01,-.011464,
-.010571,-.011064,
-.011064,-.010571,
-.011464,-.01,
-.011759,-.009368,
-.011939,-.008695,
-.012,-.008,
-.012,.008,
-.011939,.008695,
-.011759,.009368,
-.011464,.01,
-.011064,.010571,
-.010571,.011064,
-.01,.011464,
-.009368,.011759,
-.008695,.011939,
-.008,.012,
.008,.012,
.008695,.011939,
.009368,.011759,
.01,.011464,
.010571,.011064,
.011064,.010571,
.011464,.01,
.011759,.009368,
.011939,.008695,
.012,.008,
.012,-.008,
.011939,-.008695,
.011759,-.009368,
.011464,-.01,
.011064,-.010571,
.010571,-.011064,
.01,-.011464,
.009368,-.011759,
.008695,-.011939,
.008,-.012,
0.0*
%
%ADD26MACRO26*%
%ADD78C,.012*%
%ADD79C,.015*%
%ADD80C,.005*%
%ADD81C,.006*%
%ADD82C,.0065*%
%ADD83C,.00675*%
%ADD90R,.008X.019*%
%ADD88C,.04604*%
%ADD84C,.09204*%
%ADD89C,.06604*%
%ADD86C,.324*%
%ADD85C,.3222*%
%ADD87R,.008X.008*%
G75*
%LPD*%
G75*
G36*
G01X3937Y3004D02*
G02X3004Y3937I0J933D01*
G01Y10212D01*
G02X3691Y10491I400J0D01*
G03X23503Y8000I11466J11162D01*
G01X41765D01*
Y8228D01*
X41786Y8270D01*
G03X44930Y23001I-26629J13384D01*
G01X44920Y23191D01*
G03X23001Y50405I-29763J-1538D01*
G03X8000Y50584I-7845J-28752D01*
G01Y40639D01*
X7078Y39717D01*
X4222D01*
X3001Y40938D01*
Y446957D01*
X3004D01*
Y461899D01*
G02X3678Y462191I400J0D01*
G03X8000Y459248I11482J12217D01*
G01Y445477D01*
G03X23001Y445656I7156J28932D01*
G01Y445657D01*
X23147Y445697D01*
G03X39724Y491281I-7990J28712D01*
G01X39689Y491332D01*
Y496271D01*
G03X46933Y497910I164J16102D01*
G03X56894Y496479I7156J14426D01*
G03X67500Y492494I10606J12121D01*
G01X72500D01*
G03X84802Y518995I0J16106D01*
G01Y605335D01*
G02X85004Y605535I200J0D01*
G03X93600Y607931I144J16102D01*
G02X94209Y607564I210J-340D01*
G03X102926Y591657I16815J-1127D01*
G03X113057Y579564I15827J2969D01*
G01Y572226D01*
X112049D01*
X102262Y562439D01*
Y538511D01*
X112049Y528724D01*
X137477D01*
X138477Y529724D01*
X155463D01*
G02X155860Y529279I0J-400D01*
G03X155792Y526429I16001J-1808D01*
G03X155342Y525840I12568J-10068D01*
G03X171187Y497868I8764J-13509D01*
G03X181153Y496438I7156J14426D01*
G03X191712Y492494I10559J12162D01*
G01X196712D01*
G03X201786Y523886I0J16106D01*
G03X202026Y529767I-15698J3586D01*
G02X202422Y530224I396J57D01*
G01X216977D01*
X220950Y534197D01*
X223502D01*
X223975Y533724D01*
X233825D01*
Y522520D01*
X238347Y517998D01*
Y516797D01*
X239548D01*
X243869Y512476D01*
X272175D01*
Y512277D01*
G03X280709Y498118I16103J54D01*
G02X280803Y497482I-188J-353D01*
G03X299233Y471596I11350J-11423D01*
G03X310127Y470359I7155J14426D01*
G03X315925Y469279I5798J15026D01*
G01X320925D01*
G03X332237Y496850I0J16106D01*
G02Y497134I141J142D01*
G03X325960Y523899I-11312J11466D01*
G03X314764Y542933I-15701J3574D01*
G01Y581439D01*
X309390Y586813D01*
X309377Y586866D01*
G03X309276Y587243I-15604J-3978D01*
G01X309269Y587269D01*
Y595981D01*
X306764D01*
Y596439D01*
X305456Y597747D01*
Y602456D01*
X300747D01*
X296977Y606226D01*
X282401D01*
Y613714D01*
X319790D01*
G03X341972Y608053I13892J8144D01*
G01X342106Y608133D01*
X342636Y607603D01*
X342630Y607513D01*
G03X350999Y591855I16819J-1076D01*
G03X382758Y597200I15863J2771D01*
G02X383153Y597664I395J64D01*
G01X436674D01*
X448206Y609195D01*
X448345Y609094D01*
G03X463397Y606972I9508J12997D01*
G01X467110Y603259D01*
G03X468860Y598378I16550J3180D01*
G02X468594Y597796I-351J-191D01*
G03X476379Y566560I3427J-15734D01*
G01X488814D01*
X503017Y552356D01*
X502992Y552249D01*
G03X502755Y550951I15710J-3539D01*
G03X488363Y544892I-1731J-16010D01*
G03X491229Y516637I8988J-13361D01*
G03X499177Y498118I15517J-4306D01*
G02X499271Y497482I-188J-353D01*
G03X495205Y490713I11350J-11423D01*
G02X494502Y490588I-383J115D01*
G03X467318Y488651I-12969J-9713D01*
G03X461151Y489473I-5184J-15351D01*
G03X457412Y498172I-16013J-1730D01*
G03X450122Y523915I-12274J10428D01*
G03X427291Y541881I-15713J3521D01*
G03X404113Y526392I-7109J-14449D01*
G03X403663Y525803I12568J-10068D01*
G03X404859Y498081I8765J-13509D01*
G02X404953Y497445I-188J-353D01*
G03X411305Y470714I11350J-11423D01*
G01Y462498D01*
G03X406885Y456510I10395J-12298D01*
G03X433415Y439152I11715J-11048D01*
G03X436887Y444848I-11716J11047D01*
G01X443957D01*
X443995Y444831D01*
G03X466289Y456395I6505J14731D01*
G03X470063Y459170I-7611J14304D01*
G03X476348Y465524I-7930J14130D01*
G03X495760Y473121I5185J15351D01*
G01X501034D01*
X501087Y473082D01*
G03X517701Y471596I9534J12977D01*
G03X532209Y471696I7155J14426D01*
G03X534350Y471553I2141J15963D01*
G01X539350D01*
G03X555451Y488074I0J16106D01*
G02X555851Y488484I400J10D01*
G01X560975D01*
X561023Y488454D01*
G03X583500Y494120I8506J13673D01*
G01X598129D01*
G03X619566Y488085I13871J8180D01*
G03X631081Y489082I4461J15473D01*
G03X641178Y487657I7183J14412D01*
G03X647662Y486294I6484J14743D01*
G01X652663D01*
G03X668767Y502655I0J16106D01*
G03X663117Y530650I-10121J12525D01*
G01Y539614D01*
X674725D01*
X698406Y563295D01*
G03X699729Y564801I-10961J10963D01*
G03X710195Y571715I-2942J15832D01*
G01X710254Y571804D01*
X711927D01*
X714233Y574110D01*
X715966D01*
Y575843D01*
X721714Y581591D01*
Y592359D01*
G02X722345Y592685I400J0D01*
G03X723637Y591855I9746J13750D01*
G03X751715Y584134I15863J2771D01*
G02X752301Y584156I303J-261D01*
G01X812215Y524242D01*
X819727D01*
X826278Y517691D01*
X826185Y517554D01*
G03X836394Y492701I13315J-9054D01*
G01Y491238D01*
X836342Y491181D01*
G03X835068Y489591I11983J-10907D01*
G01X835009Y489506D01*
X833894D01*
Y487643D01*
X833872Y487601D01*
G03X833804Y487463I14500J-7231D01*
G01X833789Y487433D01*
X833153Y486797D01*
G03X828660Y475950I10847J-10847D01*
G01Y467000D01*
G03X833153Y456153I15340J0D01*
G01X833894Y455412D01*
Y453494D01*
X835894D01*
Y442829D01*
X835346D01*
Y439854D01*
X832051Y436559D01*
Y385473D01*
X842725Y374799D01*
X858708D01*
X858715Y374606D01*
G03X861948Y365500I16092J586D01*
G03X859802Y349937I12852J-9702D01*
G02X859394Y349393I-373J-145D01*
G01X810191Y353754D01*
X801874Y352062D01*
G02X801394Y352454I-80J392D01*
G01Y354381D01*
X801449Y354439D01*
G03X780619Y352222I-11709J11054D01*
G01Y347737D01*
X631071Y317310D01*
X631030Y317504D01*
G03X629207Y322211I-15743J-3390D01*
G02X629531Y322812I346J202D01*
G03X669866Y365354I-2267J42542D01*
G01Y388954D01*
G03X584660I-42603J0D01*
G01Y385514D01*
G02X583888Y385368I-400J1D01*
G03X568899Y395580I-14989J-5894D01*
G01X564959D01*
G03X551050Y371354I0J-16106D01*
G03X548855Y363517I13909J-8121D01*
G02X548127Y363296I-400J7D01*
G03X551006Y353820I-13222J-9192D01*
G02X551734Y354042I400J-7D01*
G03X564959Y347128I13225J9191D01*
G01X568899D01*
G03X584391Y358828I0J16106D01*
G02X585171Y358780I385J-110D01*
G03X606374Y328224I42092J6574D01*
G02X606399Y327542I-196J-349D01*
G03X599640Y317918I8888J-13428D01*
G03X596410Y315727I8234J-15615D01*
G03X577482Y306495I-4123J-15566D01*
G01X577441Y306399D01*
X577143Y306338D01*
X527013Y273205D01*
G02X526402Y273627I-221J334D01*
G03X497103Y285826I-15702J3573D01*
G02X496458Y285785I-337J215D01*
G03X494503Y287762I-12385J-10292D01*
G02X494516Y288382I259J305D01*
G03X501303Y301677I-10855J13921D01*
G03X475427Y317918I-10229J12437D01*
G03X472197Y315727I8234J-15615D01*
G03X452067Y301916I-4123J-15566D01*
G02X451426Y301642I-398J44D01*
G03X425539Y288847I-9781J-12795D01*
G01Y284646D01*
G03X426145Y280269I16105J-1D01*
G01X426153Y280242D01*
Y270760D01*
X422640D01*
G03X421960I-340J-16099D01*
G01X421954D01*
G03X406213Y253957I346J-16099D01*
G02X405440Y253796I-400J-17D01*
G03X402174Y259009I-15028J-5785D01*
G03X376587Y276250I-15374J4791D01*
G02X375934Y276534I-254J309D01*
G03X370293Y287763I-16072J-1042D01*
G02X370306Y288383I259J305D01*
G03X377091Y301677I-10857J13920D01*
G03X380792Y322192I-10229J12437D01*
G02X381120Y322793I346J201D01*
G03X421835Y365354I-1888J42561D01*
G01Y388954D01*
G03X336629I-42603J0D01*
G01Y384410D01*
G02X335847Y384291I-400J0D01*
G03X318504Y395463I-15373J-4817D01*
G03X302620Y371355I-1970J-15989D01*
G03X318504Y347245I13914J-8121D01*
G03X336211Y359790I1970J15989D01*
G02X336999Y359757I391J-85D01*
G03X358134Y328342I42233J5596D01*
G02X358152Y327659I-199J-347D01*
G03X351215Y317918I8711J-13544D01*
G03X347985Y315727I8234J-15615D01*
G03X330210Y291621I-4123J-15566D01*
G02X330060Y291056I-339J-212D01*
G03X343683Y261926I7604J-14194D01*
G02X344221Y261651I150J-371D01*
G03X347237Y255492I15641J3841D01*
G03X343756Y245492I12625J-10001D01*
G01Y235492D01*
G03X344854Y229647I16106J0D01*
G03X339268Y218082I10507J-12207D01*
G02X338832Y217700I-399J16D01*
G03X337362Y217767I-1468J-16039D01*
G01X329518D01*
G03X328722Y219641I-15190J-5346D01*
G02X328905Y220180I358J179D01*
G03X336703Y240911I-7043J14481D01*
G03X313264Y260777I-14841J6250D01*
G02X312682Y260958I-214J338D01*
G03X286435Y266008I-14821J-6297D01*
G02X285752Y266289I-283J282D01*
G03X255225Y259102I-16103J-28D01*
G03X254313Y258056I11670J-11096D01*
G01X250038Y253781D01*
G02X249413Y253856I-283J283D01*
G03X248274Y255492I-13762J-8367D01*
G03X251755Y265492I-12625J10001D01*
G01Y275492D01*
G03X246080Y287763I-16106J-1D01*
G02X246093Y288383I259J305D01*
G03X252878Y301677I-10857J13920D01*
G03X227002Y317918I-10229J12437D01*
G03X223772Y315727I8234J-15615D01*
G03X205997Y291621I-4123J-15566D01*
G02X205847Y291056I-339J-212D01*
G03X219470Y261926I7604J-14194D01*
G02X220008Y261651I150J-371D01*
G03X223024Y255492I15641J3841D01*
G03X219543Y245492I12625J-10001D01*
G01Y235492D01*
G03X220641Y229647I16106J0D01*
G03X215055Y218082I10507J-12207D01*
G02X214619Y217700I-399J16D01*
G03X213149Y217767I-1468J-16039D01*
G01X203937D01*
G03X203386Y219164I-15239J-5203D01*
G02X203603Y219699I365J164D01*
G03X212490Y240911I-5954J14962D01*
G03X189051Y260777I-14841J6250D01*
G02X188469Y260958I-214J338D01*
G03X162208Y265993I-14821J-6297D01*
G02X161525Y266258I-284J282D01*
G03X130765Y258925I-16088J-697D01*
G03X130108Y258154I11922J-10825D01*
G01X130101Y258145D01*
X125792Y253836D01*
G02X125168Y253909I-283J282D01*
G03X124062Y255492I-13732J-8416D01*
G03X127543Y265492I-12625J10001D01*
G01Y275492D01*
G03X121868Y287763I-16106J-1D01*
G02X121881Y288383I259J305D01*
G03X128666Y301677I-10857J13920D01*
G03X132376Y322178I-10229J12437D01*
G02X132708Y322778I346J200D01*
G03X173804Y365354I-1507J42576D01*
G01Y388954D01*
G03X88598I-42603J0D01*
G01Y365354D01*
G03X109898Y328460I42602J0D01*
G02X109910Y327774I-200J-347D01*
G03X102790Y317918I8527J-13660D01*
G03X99560Y315727I8234J-15615D01*
G03X81785Y291621I-4123J-15566D01*
G02X81635Y291056I-339J-212D01*
G03X95258Y261926I7604J-14194D01*
G02X95796Y261651I150J-371D01*
G03X98812Y255492I15641J3841D01*
G03X95331Y245492I12625J-10001D01*
G01Y235492D01*
G03X96429Y229647I16106J0D01*
G03X90908Y219016I10508J-12206D01*
G01X90901Y218945D01*
X89705Y217749D01*
X89618Y217753D01*
G03X88944Y217767I-671J-16092D01*
G01X79792D01*
G03X79247Y219198I-15304J-5009D01*
G02X79464Y219729I367J160D01*
G03X88278Y240911I-6027J14933D01*
G03X64839Y260777I-14841J6250D01*
G02X64257Y260958I-214J338D01*
G03X58232Y241172I-14820J-6297D01*
G02X58526Y241079I109J-168D01*
G03X58596Y240911I14899J6109D01*
G03X57386Y235951I14841J-6248D01*
G01X57371Y235767D01*
X49937D01*
G03X48291Y203639I0J-16106D01*
G02X48470Y203420I-20J-199D01*
G03X49550Y195744I16017J-1660D01*
G02X49274Y195206I-371J-149D01*
G03X67720Y172838I3813J-15645D01*
G02X67988Y172935I182J-84D01*
G03X79778Y172103I6949J14526D01*
G02X80029Y171970I60J-191D01*
G03X86812Y163059I15408J4691D01*
G03X90709Y156711I15211J4968D01*
G01X94177Y153242D01*
X94179Y153163D01*
G03X102574Y139099I16845J518D01*
G03X134012Y145960I15863J2771D01*
G02X134399Y146462I387J102D01*
G01X204492D01*
X215588Y157557D01*
G02X216191Y157514I283J-283D01*
G03X217689Y155786I12809J9591D01*
G01X218438Y155036D01*
X218431Y154945D01*
G03X226786Y139099I16805J-1265D01*
G03X258326Y145551I15863J2771D01*
G02X258715Y146042I389J91D01*
G01X303081D01*
G02X303356Y145352I0J-400D01*
G03X300213Y126125I11083J-11682D01*
G03X298382Y120371I14157J-7673D01*
G01X298374Y120303D01*
X297185Y119113D01*
G03X292498Y107798I11314J-11315D01*
G01Y85707D01*
G03X287113Y70874I10502J-12207D01*
G03X304295Y52375I15916J-2446D01*
G01X304303Y52376D01*
X310283D01*
X310294Y52375D01*
G03X313864I1785J16004D01*
G01X313875Y52376D01*
X318583D01*
X322259Y48700D01*
X322266Y48691D01*
G03X340545Y43685I12578J10054D01*
G03X350127Y43117I5701J15060D01*
G03X371294Y57853I5073J15283D01*
G03X377504Y67388I-9518J12989D01*
G03X378475Y68672I-12342J10343D01*
G03X382279Y69458I-1333J16048D01*
G01X382370Y69488D01*
X382376Y69484D01*
G03X392133Y78816I-5232J15237D01*
G01X392129Y78823D01*
X392162Y78908D01*
G03X392597Y89250I-15018J5812D01*
G03X368872Y109233I-14653J6679D01*
G02X368267Y109691I-226J330D01*
G03X365346Y125155I-15266J5124D01*
G02X365682Y125811I307J257D01*
G03X376254Y154950I1179J16059D01*
G03X375034Y160095I-16805J-1268D01*
G03X375964Y165340I-15172J5395D01*
G02X376365Y165736I400J-4D01*
G03X392419Y181742I48J16006D01*
G01Y194242D01*
G03X384123Y208269I-16007J0D01*
G02X384033Y208902I193J350D01*
G01X390702Y215572D01*
Y221063D01*
G03X405523Y242446I-390J16098D01*
G03X406500Y248714I-15111J5565D01*
G02X407273Y248876I400J18D01*
G03X417176Y239395I15028J5784D01*
G01Y234835D01*
G03X420938Y203638I5398J-15174D01*
G02X421117Y203418I-20J-199D01*
G03X424145Y192131I16007J-1755D01*
G02X423953Y191516I-323J-237D01*
G03X422955Y161467I5271J-15216D01*
G02X423133Y160878I-155J-368D01*
G01X416759Y151249D01*
Y151248D01*
G03X414467Y145827I12709J-8568D01*
G01X409122Y120345D01*
Y87902D01*
G03X409125Y87606I15328J7D01*
G03X413174Y76325I18565J296D01*
G01X413218Y76270D01*
Y74637D01*
X412943Y74362D01*
X407184D01*
X401167Y68345D01*
Y66240D01*
X401170Y66241D01*
Y60533D01*
G03X398571Y55118I4342J-5415D01*
G01Y3937D01*
G02X397638Y3004I-933J0D01*
G01X3937D01*
G37*
G36*
G01X792190Y1303434D02*
X805400Y1259897D01*
Y1256200D01*
X801255Y1252055D01*
X801198Y1252043D01*
G03X791068Y1245035I3402J-15743D01*
G03X787428Y1226656I11032J-11735D01*
G02X787003Y1226095I-364J-166D01*
G03X768438Y1210178I-2459J-15917D01*
G01Y1205978D01*
G03X768459Y1205162I16106J6D01*
G03X763429Y1193469I11076J-11693D01*
G01Y1180469D01*
G03X763431Y1180213I16106J-2D01*
G02X762776Y1179898I-400J-7D01*
G03X748892Y1183194I-10276J-12398D01*
G02X748408Y1183521I-89J390D01*
G03X742931Y1193275I-15908J-2518D01*
G02X742944Y1193895I259J305D01*
G03X749729Y1207189I-10857J13920D01*
G03X723853Y1223430I-10229J12437D01*
G03X720623Y1221239I8234J-15615D01*
G03X702848Y1197133I-4123J-15566D01*
G02X702698Y1196568I-339J-212D01*
G03X716321Y1167438I7604J-14194D01*
G02X716859Y1167163I150J-371D01*
G03X719875Y1161004I15641J3841D01*
G03X716394Y1151004I12625J-10001D01*
G01Y1141004D01*
G03X717492Y1135159I16106J0D01*
G03X712451Y1127151I10508J-12206D01*
G01X711000Y1125700D01*
X705500D01*
X705000Y1126200D01*
Y1127965D01*
X705069Y1128024D01*
G03X708228Y1148590I-10569J12149D01*
G03X683306Y1165847I-15557J4157D01*
G02X682701Y1166027I-232J326D01*
G03X666096Y1176195I-15001J-5854D01*
G02X665682Y1176735I-40J398D01*
G03X664991Y1189725I-15056J5712D01*
G03X643356Y1211397I-14347J7313D01*
G02X642798Y1211888I-181J357D01*
G03X638538Y1229148I-15166J5413D01*
G02X638702Y1229827I271J294D01*
G03X669100Y1262826I-11440J41038D01*
G03X669866Y1293097I-5100J15274D01*
G01Y1294466D01*
G03X638718Y1335500I-42603J0D01*
G01X615808D01*
G03X584660Y1294466I11455J-41034D01*
G01Y1270866D01*
G03X606912Y1233438I42603J0D01*
G02X606928Y1232744I-191J-352D01*
G03X601891Y1227960I8310J-13793D01*
G02X601338Y1227851I-331J224D01*
G03X576852Y1210264I-8938J-13395D01*
G03X578635Y1197133I15435J-4591D01*
G02X578485Y1196568I-339J-212D01*
G03X570082Y1184144I7602J-14195D01*
G01X570074Y1184074D01*
X568000Y1182000D01*
X550400D01*
X541131Y1191269D01*
X541185Y1191393D01*
G03X512979Y1206663I-14796J6354D01*
G01X508103D01*
G03X501751Y1205357I1J-16107D01*
G02X501196Y1205771I-158J368D01*
G03X492003Y1223373I-17535J2044D01*
G03X460272Y1219760I-15630J-3875D01*
G03X454422Y1197133I7802J-14087D01*
G02X454272Y1196568I-339J-212D01*
G03X446035Y1185276I7602J-14195D01*
G02X445539Y1184962I-393J72D01*
G03X426361Y1175155I-4139J-15562D01*
G03X413604Y1174511I-4707J-33423D01*
G03X412718Y1175947I-14129J-7726D01*
G03X416433Y1180408I-10314J12366D01*
G03X416445Y1204993I-10396J12298D01*
G02X416709Y1205698I259J305D01*
G03X414042Y1237647I191J16102D01*
G03X411431Y1242969I-15515J-4310D01*
G03X421835Y1270866I-32199J27897D01*
G01Y1294466D01*
G03X418453Y1311101I-42602J0D01*
G02X418560Y1311363I184J78D01*
G03X423678Y1337594I-6260J14836D01*
G02X423754Y1338220I283J283D01*
G03X429569Y1344308I-8332J13780D01*
G03X431592Y1346423I-10650J12211D01*
G03X431953Y1346680I-9216J13327D01*
G01Y1346795D01*
X432033Y1346855D01*
G03X436855Y1366803I-9660J12892D01*
G01X399318D01*
Y1351802D01*
X399319D01*
X399324Y1351607D01*
G03X404044Y1340606I16098J394D01*
G02X403968Y1339980I-283J-283D01*
G03X397733Y1333065I8331J-13781D01*
G02X397467Y1332970I-181J86D01*
G03X336629Y1294466I-18235J-38504D01*
G01Y1270866D01*
G03X358134Y1233854I42603J0D01*
G02X358152Y1233171I-199J-347D01*
G03X351215Y1223430I8711J-13544D01*
G03X347985Y1221239I8234J-15615D01*
G03X332285Y1216865I-4123J-15566D01*
G02X331597Y1217132I-288J278D01*
G03X299402Y1217095I-16097J-432D01*
G01X299397Y1216900D01*
X292896D01*
X292861Y1216914D01*
G03X288589Y1217962I-5937J-14969D01*
G02X288326Y1218620I41J398D01*
G03X272770Y1213345I-12226J10480D01*
G02X272818Y1212575I-82J-392D01*
G03X265082Y1206867I5257J-15221D01*
G03X264594Y1206874I-475J-16099D01*
G01X259594D01*
G03X253351Y1205615I-1J-16105D01*
G02X252798Y1206024I-155J368D01*
G03X252878Y1207189I-17562J1791D01*
G03X227002Y1223430I-10229J12437D01*
G03X223772Y1221239I8234J-15615D01*
G03X205997Y1197133I-4123J-15566D01*
G02X205847Y1196568I-339J-212D01*
G03X219470Y1167438I7604J-14194D01*
G02X220008Y1167163I150J-371D01*
G03X223025Y1161002I15641J3840D01*
G03X219931Y1147505I12624J-9997D01*
G03X220941Y1135411I15369J-4806D01*
G03X215119Y1124514I10208J-12458D01*
G01X215112Y1124443D01*
X213929Y1123260D01*
X213841Y1123264D01*
G03X213149Y1123279I-695J-16091D01*
G01X201469D01*
G03X199581Y1125461I-13072J-9403D01*
G02X199703Y1126117I278J288D01*
G03X209505Y1141776I-6280J14828D01*
G03X189051Y1166289I-11856J10898D01*
G02X188469Y1166470I-214J338D01*
G03X170235Y1175910I-14821J-6297D01*
G02X169752Y1176264I-85J391D01*
G03X169397Y1178454I-16035J-1476D01*
G03X168304Y1190203I-15465J4487D01*
G03X157900Y1212826I-14480J7045D01*
G01Y1215871D01*
X157980Y1215931D01*
G03X160197Y1239653I-9680J12869D01*
G03X173804Y1270866I-28996J31213D01*
G01Y1294466D01*
G03X93880Y1315014I-42603J0D01*
G02X93235Y1314937I-350J193D01*
G03X77088Y1321108I-14235J-13037D01*
G03X61789Y1333357I-16334J-4723D01*
G02X61418Y1333819I24J399D01*
G03X50270Y1351752I-15900J2547D01*
G01X50129Y1351796D01*
Y1351802D01*
G03X41206Y1351888I-4611J-15436D01*
G01X40766Y1351752D01*
G03X40422Y1351641I4773J-15379D01*
G03X40393Y1351639I1093J-16065D01*
G03X40303Y1351609I5049J-15298D01*
G01X40272Y1351598D01*
X39864D01*
G03X43529Y1319608I1516J-16031D01*
G02X43977Y1319146I53J-396D01*
G03X59859Y1299406I16777J-2761D01*
G03X88011Y1284829I19141J2494D01*
G02X88598Y1284475I187J-354D01*
G01Y1270866D01*
G03X106018Y1236503I42603J0D01*
G01X106100Y1236443D01*
Y1229975D01*
G03X102790Y1223430I12337J-10349D01*
G03X99560Y1221239I8234J-15615D01*
G03X81785Y1197133I-4123J-15566D01*
G02X81635Y1196568I-339J-212D01*
G03X95258Y1167438I7604J-14194D01*
G02X95796Y1167163I150J-371D01*
G03X98812Y1161004I15641J3841D01*
G03X95331Y1151004I12625J-10001D01*
G01Y1141004D01*
G03X96429Y1135159I16106J0D01*
G03X90899Y1124431I10508J-12206D01*
G01X90893Y1124359D01*
X89789Y1123256D01*
X89701Y1123260D01*
G03X88937Y1123279I-782J-16087D01*
G01X79759D01*
G03X79211Y1124693I-15272J-5106D01*
G02X79428Y1125226I366J162D01*
G03X88278Y1146423I-5991J14947D01*
G03X64839Y1166289I-14841J6250D01*
G02X64257Y1166470I-214J338D01*
G03X52782Y1175925I-14821J-6296D01*
G03X45747Y1187020I-15934J-2325D01*
G03X39610Y1203325I-15747J3380D01*
G01Y1210098D01*
G03X52214Y1235985I-185J16102D01*
G03X23620Y1238714I-14989J-5885D01*
G01X8000D01*
Y1099936D01*
X26851D01*
G03X31570Y1100682I-127J16102D01*
G03X44836Y1109896I-1314J16049D01*
G03X48298Y1109150I5103J15276D01*
G02X48477Y1108930I-20J-199D01*
G03X49507Y1101257I16010J-1757D01*
G02X49229Y1100721I-372J-147D01*
G03X67586Y1078194I3798J-15648D01*
G02X68117Y1078386I362J-171D01*
G03X79679Y1077584I6821J14587D01*
G02X80178Y1077322I118J-382D01*
G03X95047Y1066074I15359J4851D01*
G02X95406Y1065524I-12J-400D01*
G03X102574Y1044611I15618J-6332D01*
G03X127829Y1060462I15863J2771D01*
G03X126609Y1065607I-16805J-1268D01*
G03X126742Y1065998I-15178J5381D01*
G01X139174D01*
G02X139573Y1065568I0J-400D01*
G03X167062Y1029807I33655J-2576D01*
G01Y1024726D01*
X143800D01*
G03X118313Y1019186I-10737J-12001D01*
G03X116238Y1018560I3603J-15694D01*
G03X111714Y1018525I-2139J-15960D01*
G01X111699Y1018523D01*
X103249D01*
X100782Y1016056D01*
X96494D01*
Y1011768D01*
X94613Y1009887D01*
X94502Y1009918D01*
G03X90321Y1010474I-4182J-15447D01*
G01X82104D01*
X82089Y1010476D01*
G03X77037I-2526J-16004D01*
G01X77022Y1010474D01*
X70610D01*
G03X59295Y1005787I0J-16001D01*
G01X57338Y1003831D01*
X46757D01*
Y993256D01*
X45744D01*
Y991561D01*
X45699Y991506D01*
G03X45456Y971449I12476J-10181D01*
G01Y958425D01*
X45744Y958137D01*
Y950144D01*
X53737D01*
X53744Y950137D01*
Y950044D01*
X53837D01*
X54982Y948899D01*
X57290D01*
X57345Y948854D01*
G03X67500Y945249I10155J12500D01*
G01X72500D01*
G03X82710Y948899I0J16105D01*
G01X107152D01*
G03X115369Y943975I12011J10726D01*
G01X115423Y943962D01*
X118086Y941299D01*
X152014D01*
X156439Y945724D01*
X167153D01*
Y935033D01*
X171647Y930539D01*
Y928797D01*
X173389D01*
X177191Y924995D01*
X183456D01*
G02X183854Y924561I0J-400D01*
G03X209875Y910559I16045J-1361D01*
G02X210435Y910494I247J-314D01*
G03X216366Y935338I12665J10106D01*
G02X215800Y935702I-166J364D01*
G01Y944657D01*
G02X216212Y945057I400J0D01*
G03X216712Y945049I508J16098D01*
G01X221712D01*
G03X226298Y945716I-1J16107D01*
G01X226326Y945724D01*
X233777D01*
X248064Y960011D01*
Y972290D01*
G03X250273Y974101I-9065J13309D01*
G03X254219Y974137I1827J15999D01*
G03X268879Y966216I13881J8163D01*
G03X282170Y995140I4421J15484D01*
G02X282351Y995871I220J333D01*
G03X293162Y1022219I-1551J16028D01*
G03X297292Y1033595I-11962J10780D01*
G03X296761Y1041883I-15792J3149D01*
G02X297093Y1042408I379J128D01*
G03X310430Y1053170I-1893J15992D01*
G03X321165Y1066296I-5230J15230D01*
G01X321188Y1066470D01*
X339762D01*
G03X340056Y1066473I-16J16003D01*
G03X343437Y1065979I4006J15600D01*
G02X343793Y1065431I-16J-400D01*
G03X347257Y1047558I15656J-6238D01*
G02X347057Y1046892I-289J-276D01*
G03X366776Y1031279I3616J-15692D01*
G03X376254Y1060462I86J16103D01*
G03X375319Y1064863I-16805J-1270D01*
G02X375696Y1065398I377J135D01*
G01X400520D01*
G02X400822Y1064736I0J-400D01*
G03X429088Y1053509I12178J-10536D01*
G01X429096Y1053700D01*
X436674D01*
X436708Y1053687D01*
G03X441744Y1052636I5766J15038D01*
G03X448995Y1050898I7253J14265D01*
G01X468991D01*
G03X475211Y1044611I14671J8294D01*
G03X500093Y1034041I15863J2771D01*
G02X500692Y1033571I224J-332D01*
G03X500298Y1023643I15108J-5571D01*
G01Y995573D01*
X549087Y946783D01*
X549048Y946667D01*
G03X564350Y925534I15302J-5027D01*
G01X569350D01*
G03X570219Y925557I9J16106D01*
G01X570308Y925562D01*
X594361Y901509D01*
Y898748D01*
G02X593928Y898349I-400J0D01*
G03X577262Y877439I-1314J-16049D01*
G03X589153Y861815I16103J-81D01*
G02X589403Y861246I-105J-386D01*
G03X585189Y848400I37861J-19534D01*
G01X555178D01*
G03X451007Y847501I-51930J-18479D01*
G02X450484Y847255I-379J127D01*
G03X444687Y848335I-5798J-15026D01*
G01X440747D01*
G03X426618Y824497I0J-16106D01*
G03X440747Y800659I14129J-7732D01*
G01X444687D01*
G03X454208Y803775I-1J16106D01*
G02X454796Y803643I236J-323D01*
G03X480461Y779732I48453J26277D01*
G02X480557Y779065I-165J-364D01*
G03X475427Y770674I10518J-12194D01*
G03X472197Y768483I8234J-15615D01*
G03X454422Y744377I-4123J-15566D01*
G02X454272Y743812I-339J-212D01*
G03X467895Y714682I7604J-14194D01*
G02X468433Y714407I150J-371D01*
G03X471449Y708248I15641J3841D01*
G03X467968Y698248I12625J-10001D01*
G01Y688248D01*
G03X469066Y682403I16106J0D01*
G03X463526Y671567I10508J-12206D01*
G01X463520Y671494D01*
X462521Y670495D01*
X462432Y670500D01*
G03X461574Y670523I-860J-16083D01*
G01X452496D01*
G03X451933Y671970I-15271J-5109D01*
G02X452148Y672503I366J162D01*
G03X460915Y693667I-6074J14914D01*
G03X437476Y713533I-14841J6250D01*
G02X436894Y713714I-214J338D01*
G03X418441Y723105I-14821J-6297D01*
G02X417958Y723420I-90J389D01*
G03X413141Y732170I-15820J-3008D01*
G02Y732754I274J292D01*
G03X417689Y748650I-11012J11749D01*
G03X406500Y777348I-9975J12641D01*
G03X400174Y779505I-8247J-13831D01*
G01X399998Y779526D01*
Y780911D01*
X400100Y780968D01*
G03X421835Y818110I-20868J37142D01*
G01Y841710D01*
G03X336629I-42603J0D01*
G01Y837458D01*
G02X335849Y837332I-400J-1D01*
G03X318504Y848309I-15375J-5103D01*
G03Y816149I-1970J-16080D01*
G03X335849Y827126I1970J16080D01*
G02X336629Y827000I380J-125D01*
G01Y818110D01*
G03X357093Y781711I42603J0D01*
G01X357189Y781653D01*
Y779744D01*
X357110Y779684D01*
G03X351215Y770674I9752J-12814D01*
G03X347985Y768483I8234J-15615D01*
G03X330210Y744377I-4123J-15566D01*
G02X330060Y743812I-339J-212D01*
G03X343683Y714682I7604J-14194D01*
G02X344221Y714407I150J-371D01*
G03X347237Y708248I15641J3841D01*
G03X343756Y698248I12625J-10001D01*
G01Y688248D01*
G03X344854Y682403I16106J0D01*
G03X339324Y671675I10508J-12206D01*
G01X339318Y671603D01*
X338214Y670500D01*
X338126Y670504D01*
G03X337362Y670523I-782J-16087D01*
G01X328184D01*
G03X327636Y671937I-15272J-5106D01*
G02X327853Y672470I366J162D01*
G03X336703Y693667I-5991J14947D01*
G03X313264Y713533I-14841J6250D01*
G02X312682Y713714I-214J338D01*
G03X294293Y723120I-14821J-6297D01*
G02X293811Y723437I-89J390D01*
G03X288984Y732242I-15830J-2952D01*
G02Y732826I274J292D01*
G03X276441Y760605I-11012J11749D01*
G03X259189Y764670I-11710J-11054D01*
G02X258654Y765090I-138J376D01*
G03X227002Y770674I-16004J1781D01*
G03X223772Y768483I8234J-15615D01*
G03X205997Y744377I-4123J-15566D01*
G02X205847Y743812I-339J-212D01*
G03X219470Y714682I7604J-14194D01*
G02X220008Y714407I150J-371D01*
G03X223024Y708248I15641J3841D01*
G03X219543Y698248I12625J-10001D01*
G01Y688248D01*
G03X220641Y682403I16106J0D01*
G03X215111Y671675I10508J-12206D01*
G01X215105Y671603D01*
X214001Y670500D01*
X213913Y670504D01*
G03X213149Y670523I-782J-16087D01*
G01X198684D01*
G02X198286Y670963I0J400D01*
G03X198318Y671328I-16028J1589D01*
G03X212490Y693667I-669J16089D01*
G03X189051Y713533I-14841J6250D01*
G02X188469Y713714I-214J338D01*
G03X170072Y723118I-14821J-6297D01*
G02X169589Y723441I-89J390D01*
G03X164717Y732498I-15875J-2701D01*
G02Y733082I274J292D01*
G03X152082Y760852I-11012J11749D01*
G03X135005Y764992I-11718J-11045D01*
G02X134473Y765406I-133J377D01*
G03X132376Y774934I-16036J1465D01*
G02X132708Y775534I346J200D01*
G03X173803Y818110I-1508J42576D01*
G01Y841710D01*
G03X88597I-42603J0D01*
G01Y818110D01*
G03X109898Y781215I42603J0D01*
G02X109910Y780529I-200J-347D01*
G03X102790Y770674I8527J-13660D01*
G03X99560Y768483I8234J-15615D01*
G03X81785Y744377I-4123J-15566D01*
G02X81635Y743812I-339J-212D01*
G03X95258Y714682I7604J-14194D01*
G02X95796Y714407I150J-371D01*
G03X98812Y708248I15641J3841D01*
G03X95331Y698248I12625J-10001D01*
G01Y688248D01*
G03X96429Y682403I16106J0D01*
G03X90899Y671675I10508J-12206D01*
G01X90893Y671603D01*
X89789Y670500D01*
X89701Y670504D01*
G03X88937Y670523I-782J-16087D01*
G01X79759D01*
G03X79211Y671937I-15272J-5106D01*
G02X79428Y672470I366J162D01*
G03X88278Y693667I-5991J14947D01*
G03X64839Y713533I-14841J6250D01*
G02X64257Y713714I-214J338D01*
G03X38466Y719205I-14821J-6297D01*
G03X31102Y721007I-7402J-14301D01*
G01X8000D01*
Y646968D01*
X27144D01*
G03X31990Y647715I-2J16103D01*
G03X45288Y656997I-1314J16049D01*
G03X48298Y656394I4654J15419D01*
G02X48477Y656174I-20J-199D01*
G03X49512Y648489I16010J-1756D01*
G02X49236Y647953I-372J-148D01*
G03X52798Y616217I3851J-15636D01*
G01Y543304D01*
G02X52282Y542921I-400J0D01*
G03X31532Y526563I-4675J-15410D01*
G03X30953Y525793I12575J-10058D01*
G03X24493Y507538I8900J-13420D01*
G01X24502Y507509D01*
Y504211D01*
X15494D01*
G03X8000Y503341I-338J-29802D01*
G01Y489570D01*
G03X3678Y486627I7160J-15160D01*
G02X3004Y486919I-274J292D01*
G01Y949606D01*
X3001D01*
Y1028346D01*
X3004D01*
Y1370866D01*
G02X3937Y1371799I933J0D01*
G01X746850D01*
G03X753791Y1378740I0J6941D01*
G01Y1464567D01*
G02X754724Y1465500I933J0D01*
G01X783465D01*
G03X790406Y1472441I0J6941D01*
G01Y1654331D01*
G02X791339Y1655264I933J0D01*
G01X799298D01*
Y1650268D01*
X795402D01*
Y1472441D01*
G02X795364Y1471483I-11937J-6D01*
G03X794795Y1468683I1484J-1759D01*
G02X784008Y1460516I-11330J3758D01*
G03X783856Y1460198I9J-200D01*
G03X787009Y1456968I12991J9527D01*
G03X790600Y1450687I15424J4651D01*
G01X790653Y1450630D01*
Y1446480D01*
X782444Y1410196D01*
X788723Y1381844D01*
X780320Y1344665D01*
X780172Y1344654D01*
G03X777014Y1344119I1114J-16165D01*
G03X760743Y1339111I-4114J-15569D01*
G03X767325Y1309824I8985J-13364D01*
G03X776886Y1306587I9684J12866D01*
G03X787114Y1304304I8454J13823D01*
G03X792045Y1303437I5220J15233D01*
G01X792190Y1303434D01*
G37*
G36*
G01X69063Y972725D02*
X68063Y973725D01*
Y980725D01*
X78063Y990725D01*
X90063D01*
X90563Y990225D01*
Y984725D01*
X92563Y982724D01*
Y978225D01*
X94563Y976225D01*
Y973725D01*
X94265Y973426D01*
X91565D01*
X91364Y973225D01*
X91063D01*
X90563Y972725D01*
X69063D01*
G37*
G36*
G01X99563Y978225D02*
X100439Y979101D01*
X100561Y979053D01*
G03X102803Y979368I842J2142D01*
G01X107998D01*
Y967160D01*
X104738Y963900D01*
X61196D01*
X60457Y964639D01*
Y970082D01*
X61100Y970725D01*
X90563D01*
X92053Y972215D01*
X92147Y972206D01*
G03X92300Y972198I160J1594D01*
G01X93900D01*
G03X94174Y972222I-2J1602D01*
G01X94191Y972225D01*
X95063D01*
X96063Y973225D01*
Y977225D01*
X97063Y978225D01*
X99563D01*
G37*
G36*
G01X131263Y543725D02*
X118263D01*
X117263Y544725D01*
Y556225D01*
X118263Y557225D01*
X131263D01*
X132263Y556225D01*
Y544725D01*
X131263Y543725D01*
G37*
G36*
G01X118667Y993458D02*
X122041Y990084D01*
Y979902D01*
X121862Y979723D01*
Y967438D01*
X121485Y967061D01*
X109904D01*
X109515Y967450D01*
X109559Y967555D01*
Y990175D01*
G03X110265Y992597I-1496J1750D01*
G01X110256Y992626D01*
Y994618D01*
X111957Y996319D01*
G02X112298Y996178I141J-141D01*
G01Y995998D01*
X115702D01*
Y996074D01*
X115948Y996177D01*
X117483Y994642D01*
X117497Y994591D01*
G03X118616Y993472I1544J425D01*
G01X118667Y993458D01*
G37*
G36*
G01X121028Y1001366D02*
Y998764D01*
X120423Y998159D01*
X115702D01*
Y998602D01*
X112298D01*
Y998159D01*
X110563D01*
X109197Y999525D01*
X109163D01*
Y1003222D01*
X109463Y1003522D01*
X118063D01*
Y1003525D01*
X119605D01*
X119617Y1003338D01*
G03X121028Y1001366I2297J153D01*
G37*
G36*
G01X143994Y181742D02*
Y194242D01*
G03X128415Y210242I-16006J0D01*
G02X128143Y210925I11J400D01*
G01X138762Y221544D01*
G03X157833Y242630I3925J15617D01*
G03X158740Y246831I-15146J5468D01*
G02X159491Y246990I399J-31D01*
G03X182444Y241172I14158J7671D01*
G02X182738Y241079I109J-168D01*
G03X182808Y240911I14899J6109D01*
G03X181598Y235951I14841J-6248D01*
G01X181583Y235767D01*
X174149D01*
G03X172458Y203644I0J-16106D01*
G02X172810Y203182I-42J-397D01*
G03X173353Y195680I15889J-2621D01*
G02X173079Y195174I-381J-121D01*
G03X161314Y178885I4320J-15513D01*
G02X160915Y178466I-399J-19D01*
G01X144140D01*
G02X143746Y178936I0J400D01*
G03X143994Y181742I-15758J2807D01*
G37*
G36*
G01X166263Y566225D02*
X167139Y567101D01*
X167261Y567053D01*
G03X169503Y567368I842J2142D01*
G01X174698D01*
Y555160D01*
X164263Y544725D01*
X135763D01*
X134263Y546225D01*
Y557725D01*
X135263Y558725D01*
X157263D01*
X158753Y560215D01*
X158847Y560206D01*
G03X159000Y560198I160J1594D01*
G01X160600D01*
G03X160874Y560222I-2J1602D01*
G01X160891Y560225D01*
X161763D01*
X162763Y561225D01*
Y565225D01*
X163763Y566225D01*
X166263D01*
G37*
G36*
G01X135763Y560725D02*
X134763Y561725D01*
Y568725D01*
X144763Y578725D01*
X156763D01*
X157263Y578225D01*
Y572725D01*
X159263Y570724D01*
Y566225D01*
X161263Y564225D01*
Y561725D01*
X160965Y561426D01*
X158265D01*
X158064Y561225D01*
X157763D01*
X157263Y560725D01*
X135763D01*
G37*
G36*
G01X227563Y960725D02*
X163489D01*
X161563Y962651D01*
Y988725D01*
X165063Y992225D01*
X224959D01*
X225204Y991980D01*
Y990815D01*
X225837Y990182D01*
X230106D01*
X233063Y987225D01*
Y966225D01*
X227563Y960725D01*
G37*
G36*
G01X124300Y956300D02*
X123063Y957537D01*
Y967048D01*
X123552D01*
Y979368D01*
X128844D01*
Y979468D01*
X132612D01*
X133044Y979900D01*
X145713D01*
X147563Y978050D01*
Y958063D01*
X145800Y956300D01*
X124300D01*
G37*
G36*
G01X153386Y1004505D02*
X153435Y1004554D01*
Y1008597D01*
X154563Y1009725D01*
X157460D01*
X158460Y1008725D01*
Y997122D01*
X157763Y996425D01*
X150263D01*
X149563Y997125D01*
Y1000061D01*
G02X150061Y1000449I400J0D01*
G03X150456Y1000400I393J1552D01*
G01X152056D01*
G03X153658Y1002001I0J1602D01*
G01Y1003601D01*
G03X153459Y1004374I-1601J0D01*
G01X153386Y1004505D01*
G37*
G36*
G01X156526Y1100802D02*
X156480Y1100829D01*
G03X144207Y1102448I-8081J-13929D01*
G02X143710Y1102759I-104J386D01*
G03X128499Y1115752I-15722J-3005D01*
G02X128229Y1116434I13J400D01*
G01X138833Y1127038D01*
X138941Y1127012D01*
G03X158211Y1138395I3746J15661D01*
G03X165419Y1145838I-7349J14328D01*
G02X165971Y1146019I362J-171D01*
G03X177130Y1144451I7679J14154D01*
G02X177610Y1143984I87J-391D01*
G03X177328Y1141472I15812J-3047D01*
G01X177322Y1141279D01*
X174149D01*
G03X158363Y1128366I0J-16106D01*
G03X157087Y1101450I14865J-14193D01*
G02X156773Y1100802I-314J-248D01*
G01X156526D01*
G37*
G36*
G01X209763Y545225D02*
X206763Y548225D01*
X198263D01*
X190252Y556236D01*
Y567368D01*
X195544D01*
Y567468D01*
X199312D01*
X199744Y567900D01*
X212413D01*
X214263Y566050D01*
Y550225D01*
X212263Y548225D01*
Y546725D01*
X210763Y545225D01*
X209763D01*
G37*
G36*
G01X185367Y581458D02*
X188741Y578084D01*
Y567902D01*
X188562Y567723D01*
Y556227D01*
X188741Y556048D01*
Y555617D01*
X188185Y555061D01*
X176604D01*
X176215Y555450D01*
X176259Y555555D01*
Y578175D01*
G03X176965Y580597I-1496J1750D01*
G01X176956Y580626D01*
Y582618D01*
X178657Y584319D01*
G02X178998Y584178I141J-141D01*
G01Y583998D01*
X182402D01*
Y584074D01*
X182648Y584177D01*
X184183Y582642D01*
X184197Y582591D01*
G03X185316Y581472I1544J425D01*
G01X185367Y581458D01*
G37*
G36*
G01X187728Y589366D02*
Y586764D01*
X187123Y586159D01*
X182402D01*
Y586602D01*
X178998D01*
Y586159D01*
X177263D01*
X175897Y587525D01*
X175863D01*
Y591222D01*
X176163Y591522D01*
X184763D01*
Y591525D01*
X186305D01*
X186317Y591338D01*
G03X187728Y589366I2297J153D01*
G37*
G36*
G01X220086Y592505D02*
X220135Y592554D01*
Y596597D01*
X221263Y597725D01*
X224160D01*
X225160Y596725D01*
Y585122D01*
X224463Y584425D01*
X216963D01*
X216263Y585125D01*
Y588061D01*
G02X216761Y588449I400J0D01*
G03X217156Y588400I393J1552D01*
G01X218756D01*
G03X220358Y590001I0J1602D01*
G01Y591601D01*
G03X220159Y592374I-1601J0D01*
G01X220086Y592505D01*
G37*
G36*
G01X199174Y939996D02*
X183405D01*
X182154Y941247D01*
Y952316D01*
X184063Y954225D01*
X198063D01*
X200697Y951591D01*
Y941519D01*
X199174Y939996D01*
G37*
G36*
G01X224918Y994080D02*
X224563Y993725D01*
X203063D01*
X202063Y994725D01*
Y1001725D01*
X203563Y1003225D01*
X224063D01*
X225063Y1002225D01*
Y996065D01*
G03X224879Y994197I2000J-1140D01*
G01X224918Y994080D01*
G37*
G36*
G01X197058Y1005825D02*
X185563D01*
X182063Y1009325D01*
Y1019733D01*
X183555Y1021225D01*
X198806D01*
X200701Y1019330D01*
Y1009468D01*
X197058Y1005825D01*
G37*
G36*
G01X230277Y1018226D02*
X215702D01*
Y1025544D01*
X211153Y1030093D01*
Y1031703D01*
X209543D01*
X205020Y1036226D01*
X194936D01*
G02X194682Y1036935I0J400D01*
G03X206556Y1068335I-21454J26058D01*
G02X206951Y1068798I395J63D01*
G01X210777D01*
X210827Y1068765D01*
G03X219259Y1066074I8924J13407D01*
G02X219618Y1065524I-12J-400D01*
G03X226786Y1044611I15618J-6332D01*
G03X257821Y1052776I15863J2770D01*
G02X258511Y1053160I377J135D01*
G03X268558Y1047299I12590J10040D01*
G02X268810Y1046658I-63J-395D01*
G03X265408Y1036149I12690J-9913D01*
G03X268838Y1022681I15792J-3149D01*
G03X267241Y1020586I11965J-10777D01*
G03X251931Y1018938I-6141J-14886D01*
G03X233149Y1015923I-7331J-14338D01*
G02X232582Y1015921I-284J281D01*
G01X230277Y1018226D01*
G37*
G36*
G01X268206Y181737D02*
Y194242D01*
G03X259792Y208333I-16006J0D01*
G02X259699Y208968I190J352D01*
G01X265702Y214972D01*
Y220678D01*
G02X266121Y221077I400J0D01*
G03X282061Y242586I778J16084D01*
G03X282958Y246820I-15162J5424D01*
G02X283708Y246981I399J-30D01*
G03X306657Y241172I14154J7680D01*
G02X306951Y241079I109J-168D01*
G03X307021Y240911I14899J6109D01*
G03X305811Y235951I14841J-6248D01*
G01X305796Y235767D01*
X298362D01*
G03X296723Y203638I0J-16106D01*
G02X296902Y203418I-20J-199D01*
G03X297910Y195799I16010J-1758D01*
G02X297637Y195266I-372J-146D01*
G03X285553Y178475I3975J-15605D01*
G02X285154Y178046I-399J-29D01*
G01X268272D01*
G02X267880Y178526I0J400D01*
G03X268206Y181737I-15680J3214D01*
G37*
G36*
G01X266016Y527477D02*
X250083D01*
X248826Y528734D01*
Y540288D01*
X250763Y542225D01*
X264763D01*
X267263Y539725D01*
Y530170D01*
X267262Y530168D01*
Y528723D01*
X266016Y527477D01*
G37*
G36*
G01X294263Y548725D02*
X230189D01*
X228263Y550651D01*
Y576725D01*
X231763Y580225D01*
X291260D01*
X291582Y579903D01*
Y578532D01*
X291953Y578161D01*
X296827D01*
X299763Y575225D01*
Y554225D01*
X294263Y548725D01*
G37*
G36*
G01X265654Y593825D02*
X250664D01*
X248842Y595647D01*
Y607396D01*
X250671Y609225D01*
X265541D01*
X267400Y607366D01*
Y595571D01*
X265654Y593825D01*
G37*
G36*
G01X268206Y645720D02*
Y646998D01*
G03X252711Y662996I-16006J0D01*
G02X252441Y663678I13J400D01*
G01X263045Y674282D01*
X263153Y674256D01*
G03X282346Y694466I3746J15661D01*
G02X282616Y694962I384J113D01*
G03X286072Y696449I-4593J15434D01*
G03X306657Y693928I11790J10968D01*
G02X306951Y693835I109J-168D01*
G03X307021Y693667I14899J6109D01*
G03X305811Y688707I14841J-6248D01*
G01X305796Y688523D01*
X298362D01*
G03X296723Y656394I0J-16106D01*
G02X296902Y656174I-20J-199D01*
G03X297910Y648555I16010J-1758D01*
G02X297637Y648022I-372J-146D01*
G03X292537Y645720I3974J-15605D01*
G01X268206D01*
G37*
G36*
G01X269763Y581725D02*
X268763Y582725D01*
Y589725D01*
X270263Y591225D01*
X290763D01*
X291763Y590225D01*
Y584065D01*
G03X291579Y582197I2000J-1140D01*
G01X291618Y582080D01*
X291263Y581725D01*
X269763D01*
G37*
G36*
G01X298362Y1141279D02*
G03X296917Y1109132I0J-16106D01*
G02X297277Y1108679I-36J-398D01*
G03X297966Y1101374I15955J-2180D01*
G02X297677Y1100857I-379J-127D01*
G03X292252Y1098476I3649J-15684D01*
G01X268206D01*
Y1099755D01*
G03X267582Y1104180I-16006J-1D01*
G02X267891Y1104684I384J111D01*
G03X278128Y1129631I-3027J15816D01*
G03X281808Y1135087I-11229J11543D01*
G03X285692Y1140224I-10644J12084D01*
G03X291480Y1152091I-10307J12372D01*
G03X291791Y1152522I-12901J9637D01*
G02X292370Y1152606I329J-228D01*
G03X305883Y1149429I10082J12556D01*
G02X306121Y1149276I43J-195D01*
G03X307021Y1146423I15741J3397D01*
G03X305811Y1141463I14841J-6248D01*
G01X305796Y1141279D01*
X298362D01*
G37*
G36*
G01X293644Y1187311D02*
G03X302529Y1205925I-6719J14635D01*
G02X303221Y1206282I388J98D01*
G03X327077Y1205508I12279J10418D01*
G02X327765Y1205241I288J-278D01*
G03X330210Y1197133I16097J432D01*
G02X330060Y1196568I-339J-212D01*
G03X323225Y1189505I7602J-14195D01*
G03X315576Y1175674I8454J-13706D01*
G02X314868Y1175416I-400J-3D01*
G03X294485Y1179156I-12416J-10254D01*
G02X293896Y1179587I-198J348D01*
G03X293644Y1187311I-15750J3352D01*
G37*
G36*
G01X392419Y634497D02*
Y646998D01*
G03X376924Y662996I-16006J0D01*
G02X376654Y663678I13J400D01*
G01X387258Y674282D01*
G03X406518Y694605I3854J15635D01*
G02X406653Y694855I191J58D01*
G03X410308Y696423I-4473J15470D01*
G03X430869Y693928I11766J10994D01*
G02X431163Y693835I109J-168D01*
G03X431233Y693667I14899J6109D01*
G03X430023Y688707I14841J-6248D01*
G01X430008Y688523D01*
X422574D01*
G03X421033Y656385I0J-16106D01*
G02X421213Y656164I-19J-199D01*
G03X422249Y648489I16011J-1746D01*
G02X421973Y647953I-372J-148D01*
G03X409871Y630122I3851J-15636D01*
G02X409475Y629668I-396J-54D01*
G01X392210D01*
G02X391825Y630176I0J400D01*
G03X392419Y634497I-15412J4320D01*
G37*
G36*
G01X592780Y593537D02*
X575778D01*
G03X573652Y593396I1J-16106D01*
G03X569622Y593454I-2245J-15946D01*
G03X564836Y593330I-1981J-15981D01*
G03X547101Y582809I-2557J-15899D01*
G03X543845Y579211I10176J-12481D01*
G02X543278Y579107I-333J220D01*
G03X536395Y581936I-9398J-13077D01*
G03X531906Y584125I-9217J-13204D01*
G03X508898Y590544I-14407J-7194D01*
G01X508762Y590459D01*
X506997Y592224D01*
X507012Y592323D01*
G03X505588Y601601I-15938J2302D01*
G01X505526Y601728D01*
X516700Y612902D01*
X587279D01*
G03X591090Y613363I-2J16002D01*
G03X591897Y613318I1300J16054D01*
G02X592256Y612768I-12J-400D01*
G03X596692Y593828I15618J-6331D01*
G02X596338Y593139I-265J-299D01*
G03X592780Y593537I-3558J-15708D01*
G37*
G36*
G01X507107Y765371D02*
G03X505374Y774273I-16033J1498D01*
G02X505712Y774857I355J184D01*
G03X556986Y817657I-2464J55064D01*
G02X557560Y817924I390J-88D01*
G03X564959Y816123I7401J14305D01*
G01X568899D01*
G03X583888Y826335I0J16106D01*
G02X584660Y826189I372J-147D01*
G01Y818110D01*
G03X606374Y780980I42602J0D01*
G02X606399Y780298I-196J-349D01*
G03X599640Y770674I8888J-13428D01*
G03X596410Y768483I8234J-15615D01*
G03X578635Y744377I-4123J-15566D01*
G02X578485Y743812I-339J-212D01*
G03X592108Y714682I7604J-14194D01*
G02X592646Y714407I150J-371D01*
G03X595662Y708248I15641J3841D01*
G03X592181Y698248I12625J-10001D01*
G01Y688248D01*
G03X593279Y682403I16106J0D01*
G03X587739Y671567I10508J-12206D01*
G01X587733Y671494D01*
X586734Y670495D01*
X586645Y670500D01*
G03X585787Y670523I-860J-16083D01*
G01X576709D01*
G03X576146Y671970I-15271J-5109D01*
G02X576361Y672503I366J162D01*
G03X585128Y693667I-6074J14914D01*
G03X561689Y713533I-14841J6250D01*
G02X561107Y713714I-214J338D01*
G03X542587Y723090I-14821J-6296D01*
G02X542101Y723411I-92J389D01*
G03X537237Y732423I-15867J-2745D01*
G02Y733007I274J292D01*
G03X524602Y760777I-11012J11749D01*
G03X507636Y764956I-11718J-11045D01*
G02X507107Y765371I-131J378D01*
G37*
G36*
G01X688554Y977461D02*
G03X686751Y977359I7J-16106D01*
G01X686740Y977358D01*
X571173D01*
X571162Y977359D01*
G03X569359Y977461I-1810J-16004D01*
G01X564347D01*
G03X562474Y977352I-2J-16106D01*
G01X562378Y977340D01*
X531302Y1008415D01*
Y1012205D01*
G03X546839Y1026867I-502J16095D01*
G02X547364Y1027211I399J-36D01*
G03X555665Y1026718I5073J15283D01*
G03X564278Y1056643I357J16099D01*
G02X564200Y1057269I205J343D01*
G01X577801Y1070870D01*
X580913D01*
X580971Y1070811D01*
G03X591897Y1066074I11416J11362D01*
G02X592256Y1065524I-12J-400D01*
G03X599424Y1044611I15618J-6332D01*
G03X624679Y1060462I15863J2771D01*
G03X623459Y1065607I-16805J-1268D01*
G03X623717Y1066398I-15175J5387D01*
G01X629157D01*
X629175Y1066218D01*
G03X637669Y1053567I16025J1582D01*
G03X655254Y1032669I32410J9425D01*
G02X655289Y1031970I-176J-359D01*
G03X658272Y1003175I8511J-13670D01*
G03X687546Y1010776I16028J-1555D01*
G02X687738Y1011379I329J227D01*
G03X693427Y1038044I-5538J15121D01*
G02X693429Y1038620I279J287D01*
G03X703057Y1070185I-23350J24373D01*
G02X703447Y1070670I391J85D01*
G01X705126D01*
X705184Y1070611D01*
G03X716033Y1065877I11415J11362D01*
G02X716392Y1065332I-14J-400D01*
G03X723637Y1044611I15695J-6139D01*
G03X726198Y1038307I15863J2772D01*
G01Y978728D01*
X720460Y972990D01*
Y968640D01*
X707927D01*
G03X693563Y977461I-14364J-7285D01*
G01X688554D01*
G37*
G36*
G01X598551Y8000D02*
X697632D01*
Y23001D01*
X697608Y23173D01*
G03X688567Y36967I-19164J-2701D01*
G03X642532Y67656I-33745J-747D01*
G03X639464Y69468I-11334J-15687D01*
G02X639557Y70222I171J362D01*
G01X726475Y87496D01*
X786713Y74877D01*
X786722Y74724D01*
G03X791717Y63968I16079J929D01*
G02X791700Y63372I-275J-290D01*
G03X790367Y62107I10402J-12296D01*
G03X782996Y48575I8736J-13532D01*
G01Y43574D01*
G03X786406Y33664I16106J0D01*
G03X788185Y28264I15944J2260D01*
G02X787863Y27675I-352J-190D01*
G03X777658Y23001I1183J-16060D01*
G01X777600Y22943D01*
X777590D01*
G03X773346Y8000I11455J-11328D01*
G01X783465D01*
G02X794689Y126I0J-11937D01*
G01X796727D01*
Y-4870D01*
X791339D01*
G02X790406Y-3937I0J933D01*
G03X783465Y3004I-6941J0D01*
G01X594488D01*
G02X593555Y3937I0J933D01*
G01Y55118D01*
G03X591770Y59765I-6941J0D01*
G01Y65229D01*
G02X592363Y65580I400J0D01*
G02X598551Y55118I-5749J-10461D01*
G01Y8000D01*
G37*
G36*
G01X640463Y588405D02*
X628107D01*
X626734Y589778D01*
Y607106D01*
X627733Y608105D01*
X650063D01*
X651163Y607005D01*
Y592336D01*
X650563Y591736D01*
X643794D01*
X640463Y588405D01*
G37*
G36*
G01X710000Y670523D02*
X700822D01*
G03X700274Y671937I-15272J-5106D01*
G02X700491Y672470I366J162D01*
G03X709341Y693667I-5991J14947D01*
G03X685902Y713533I-14841J6250D01*
G02X685320Y713714I-214J338D01*
G03X666994Y723133I-14820J-6297D01*
G02X666513Y723452I-87J391D01*
G03X661671Y732340I-15845J-2869D01*
G02Y732924I274J292D01*
G03X649036Y760694I-11012J11749D01*
G03X631838Y764791I-11718J-11045D01*
G02X631304Y765208I-136J376D01*
G03X629207Y774967I-16017J1663D01*
G02X629531Y775568I346J202D01*
G03X669866Y818110I-2267J42542D01*
G01Y841712D01*
G03X662722Y865326I-42603J-1D01*
G02X663055Y865948I333J222D01*
G01X695605D01*
Y865394D01*
X697472D01*
X697530Y865338D01*
G03X697789Y865094I11173J11601D01*
G01X697854Y865035D01*
Y864715D01*
G03X702300Y853849I15503J1D01*
G01Y843737D01*
G03X740837Y836882I15810J-22871D01*
G01X740800Y836934D01*
Y843515D01*
G03X743640Y845382I-7376J14314D01*
G03X746967Y846110I-1759J16006D01*
G01X746998Y846120D01*
X750288D01*
Y847654D01*
X750383Y847712D01*
G03X751165Y848230I-8498J13678D01*
G01X751217Y848267D01*
X757590D01*
X759169Y846688D01*
X775597D01*
X785593Y856684D01*
Y884093D01*
X791600Y890100D01*
X801869D01*
X839099Y852870D01*
X856030D01*
X857600Y851300D01*
Y848341D01*
G03X852718Y824826I8063J-13938D01*
G03X851670Y820707I14945J-5995D01*
G01X851649Y820530D01*
X788646D01*
X748404Y780288D01*
G03X723853Y770674I-8904J-13418D01*
G03X720623Y768483I8234J-15615D01*
G03X702848Y744377I-4123J-15566D01*
G02X702698Y743812I-339J-212D01*
G03X716321Y714682I7604J-14194D01*
G02X716859Y714407I150J-371D01*
G03X719875Y708248I15641J3841D01*
G03X716394Y698248I12625J-10001D01*
G01Y688248D01*
G03X717492Y682403I16106J0D01*
G03X711906Y670838I10507J-12207D01*
G02X711470Y670456I-399J16D01*
G03X710000Y670523I-1468J-16039D01*
G37*
G36*
G01X675153Y928859D02*
G03X681872Y929311I2303J15937D01*
G02X682382Y928926I110J-385D01*
G01Y908975D01*
X684026Y907331D01*
Y904546D01*
X686811D01*
X687677Y903680D01*
Y896952D01*
X642765D01*
X605800Y933917D01*
Y941900D01*
X609252Y945352D01*
X651154D01*
G02X651332Y944594I0J-400D01*
G03X674698Y928502I7242J-14494D01*
G02X675153Y928859I398J-39D01*
G37*
G36*
G01X679763Y581355D02*
X655263D01*
X653263Y583355D01*
Y613355D01*
X655263Y615355D01*
X684763D01*
X685763Y614355D01*
Y589855D01*
X685263Y589355D01*
X681763D01*
X680763Y588355D01*
Y582355D01*
X679763Y581355D01*
G37*
G36*
G01X705713Y586805D02*
X688397D01*
X687713Y587489D01*
Y612805D01*
X690213Y615305D01*
X705213D01*
X706713Y613805D01*
Y587805D01*
X705713Y586805D01*
G37*
G36*
G01X705456Y616956D02*
X688381D01*
X688150Y617187D01*
Y625967D01*
X690501Y628318D01*
X705538D01*
X706699Y627157D01*
Y618199D01*
X705456Y616956D01*
G37*
G36*
G01X704383Y927189D02*
X699383D01*
X698383Y928189D01*
Y943876D01*
X703217Y948710D01*
X715108D01*
X720037Y953639D01*
X729433D01*
X732083Y950989D01*
Y943389D01*
X710283D01*
X709233Y942339D01*
X705033D01*
X702383Y939689D01*
Y936189D01*
X705383Y933189D01*
Y928189D01*
X704383Y927189D01*
G37*
G36*
G01X706383Y915689D02*
X704963Y914269D01*
X704867Y914280D01*
G03X704683Y914290I-179J-1591D01*
G01X703083D01*
G03X702553Y914200I-1J-1601D01*
G01X702521Y914189D01*
X698383D01*
X697383Y915189D01*
Y924189D01*
X698383Y925189D01*
X704883D01*
X706383Y923689D01*
Y915689D01*
G37*
G36*
G01X727878Y885498D02*
Y889320D01*
X721774D01*
Y889298D01*
X721221Y889851D01*
G03X720683Y890389I-1369J-831D01*
G01X719883Y891189D01*
X717289D01*
X716588Y891890D01*
X716582D01*
X716383Y892089D01*
Y894689D01*
X717183Y895489D01*
X722884D01*
X726128Y892245D01*
Y891606D01*
X726766D01*
X726885Y891488D01*
X732381D01*
X732399Y891506D01*
X733067D01*
X733085Y891488D01*
X733886D01*
Y885498D01*
X727878D01*
G37*
G36*
G01X722813Y857666D02*
X722583Y857895D01*
Y861132D01*
X722423Y861292D01*
Y868071D01*
X720629Y869865D01*
Y877635D01*
X726742Y883748D01*
X728096D01*
Y879960D01*
X727723Y879587D01*
X727651Y879580D01*
G03X725492Y877421I232J-2391D01*
G01X725485Y877349D01*
X724082Y875946D01*
Y875216D01*
G03X723824Y874344I1343J-872D01*
G01Y872744D01*
G03X724082Y871872I1601J0D01*
G01Y870483D01*
X725783Y868782D01*
Y857895D01*
X725553Y857666D01*
X722813D01*
G37*
G36*
G01X746583Y885689D02*
X745262Y887010D01*
X745246Y887051D01*
G03X743851Y888446I-2246J-851D01*
G01X743810Y888462D01*
X742683Y889589D01*
X739483D01*
X739214Y889320D01*
X735384D01*
Y891606D01*
X735636D01*
Y892442D01*
X740883Y897689D01*
X749184D01*
X749385Y897488D01*
X752381D01*
X752582Y897689D01*
X766883D01*
X767883Y896689D01*
Y886689D01*
X766883Y885689D01*
X746583D01*
G37*
G36*
G01X749129Y926189D02*
G03X747190Y926983I-1746J-1500D01*
G01X747097Y926975D01*
X746883Y927189D01*
Y948848D01*
X756724D01*
X756883Y948689D01*
Y929689D01*
X753383Y926189D01*
X749129D01*
G37*
G36*
G01X710350Y918593D02*
X708128Y920815D01*
Y932136D01*
X706584Y933680D01*
Y933687D01*
X703636Y936635D01*
Y939243D01*
X705468Y941075D01*
X709674D01*
X710566Y941967D01*
X733207D01*
X734405Y943165D01*
Y948953D01*
X735652Y950200D01*
X743000D01*
X743900Y949300D01*
Y926973D01*
X743473Y926546D01*
X742802D01*
X742528Y926272D01*
Y923072D01*
X743557Y922043D01*
X747791D01*
X748084Y921750D01*
Y918846D01*
X747831Y918593D01*
X710350D01*
G37*
G36*
G01X727778Y893004D02*
Y893256D01*
X726816D01*
X722883Y897189D01*
X714883D01*
X710383Y901689D01*
Y910189D01*
X712883Y912689D01*
X730383D01*
X732383Y910689D01*
Y897610D01*
X732034D01*
Y893004D01*
X727778D01*
G37*
G36*
G01X733668Y893256D02*
Y896974D01*
X734883Y898189D01*
Y904689D01*
X735883Y905689D01*
X738883D01*
X739383Y905189D01*
Y904886D01*
G03X739380Y904802I1598J-99D01*
G01Y903402D01*
G03X739383Y903318I1601J15D01*
G01Y898189D01*
X734450Y893256D01*
X733668D01*
G37*
G36*
G01X742883Y900189D02*
X740584Y902488D01*
Y905687D01*
X740483Y905789D01*
X742883Y908189D01*
X747383D01*
X747883Y907689D01*
Y901189D01*
X746883Y900189D01*
X742883D01*
G37*
G36*
G01X881644Y1008625D02*
X881614Y1008558D01*
G03X882090Y994671I14757J-6446D01*
G03X880078Y981702I13526J-8739D01*
G03X884344Y967110I15759J-3312D01*
G03X891300Y957820I15502J4358D01*
G01Y950140D01*
G03X888477Y947128I10241J-12427D01*
G03X880578Y927772I7392J-14306D01*
G03X881383Y922472I16101J-266D01*
G03X880797Y912806I15037J-5762D01*
G02X880456Y912312I-388J-97D01*
G03X870370Y885544I1877J-15991D01*
G02X870073Y884876I-297J-268D01*
G01X852355D01*
X790978Y946253D01*
G02X791007Y946846I282J283D01*
G03X770304Y971513I-10208J12454D01*
G03X764839Y967852I6098J-15012D01*
G01X758202D01*
Y1039621D01*
G02X758624Y1040020I400J0D01*
G03Y1072180I876J16080D01*
G02X758202Y1072579I-22J399D01*
G01Y1073127D01*
X757953Y1073377D01*
G02X758012Y1073991I283J283D01*
G03X765057Y1087254I-8962J13263D01*
G01Y1099754D01*
G03X749468Y1115755I-16006J0D01*
G02X749195Y1116437I10J400D01*
G01X756919Y1124161D01*
X756996Y1124164D01*
G03X772030Y1143461I-746J16086D01*
G03X772252Y1146123I-15780J2656D01*
G01Y1149954D01*
X772253Y1149965D01*
G03X767917Y1162849I-16003J1786D01*
G03X768601Y1167756I-15417J4650D01*
G02X769257Y1168070I400J6D01*
G03X777211Y1164532I10279J12399D01*
G03X789264Y1154437I15052J5729D01*
G03X791992Y1151657I12773J9806D01*
G02X792026Y1151062I-249J-313D01*
G03X813482Y1152287I11412J-11362D01*
G02X813448Y1152882I249J313D01*
G03X813803Y1175238I-11412J11362D01*
G02X813996Y1175898I293J273D01*
G03X823532Y1182765I-3995J15603D01*
G03X826784Y1187060I-11034J11733D01*
G02X827522Y1186991I355J-185D01*
G01X881644Y1008625D01*
G37*
G36*
G01X949008Y785163D02*
G03X938311Y776503I3812J-15645D01*
G03X936000Y774427I9556J-12961D01*
G03X928414Y761495I8500J-13677D01*
G03X930269Y741818I13586J-8645D01*
G02X930220Y741226I-291J-274D01*
G03X929678Y740798I11907J-15635D01*
G01X869182D01*
X848299Y707517D01*
Y701214D01*
X848199Y701114D01*
Y677386D01*
X858736Y666849D01*
X878351D01*
X879800Y665400D01*
Y658903D01*
X866439Y639092D01*
X850858Y558918D01*
X851096Y557696D01*
X846400Y553000D01*
X836231D01*
X832983Y556248D01*
X825471D01*
X759720Y621999D01*
G02X759735Y622580I282J283D01*
G03X765057Y634498I-10683J11918D01*
G01Y646999D01*
G03X762909Y655008I-16006J0D01*
G03X770191Y672359I-8409J13733D01*
G03X771003Y679485I-15191J5340D01*
G01X771002Y679496D01*
Y688693D01*
G02X771635Y689018I400J0D01*
G03X839060Y723644I24821J34626D01*
G01Y747244D01*
G03X809676Y787744I-42603J0D01*
G02X809800Y788524I125J380D01*
G01X876877D01*
X876888Y788523D01*
G03X892705Y796628I1784J16004D01*
G03X901221Y820489I-5105J15272D01*
G03X901683Y823593I-15621J3911D01*
G03X907923Y827168I-4683J15407D01*
G03X902193Y858583I-4923J15332D01*
G02X901778Y859046I-20J400D01*
G03X891805Y876592I-15896J2572D01*
G03X888473Y880818I-14134J-7717D01*
G02X888586Y881483I268J297D01*
G03X897604Y891217I-6253J14837D01*
G03X902751Y890432I4969J15317D01*
G03X918829Y885419I12125J10597D01*
G01X919014Y885466D01*
X949296Y785668D01*
G02X949008Y785163I-383J-116D01*
G37*
G36*
G01X765383Y861689D02*
X763883Y863189D01*
Y865189D01*
X763914Y865220D01*
Y867130D01*
X762552Y868492D01*
X762539Y868547D01*
G03X761873Y869743I-2435J-573D01*
G01X760140Y871476D01*
X759568D01*
X758855Y872189D01*
X755911D01*
X755000Y873100D01*
Y878600D01*
X755700Y879300D01*
X759411D01*
X760800Y880689D01*
X767853D01*
X770592Y877950D01*
Y862898D01*
X769383Y861689D01*
X765383D01*
G37*
G36*
G01X753383Y900189D02*
X751891Y898697D01*
X751805Y898699D01*
G03X751768Y898700I-62J-1600D01*
G01X750168D01*
G03X749995Y898690I6J-1602D01*
G01X749985Y898689D01*
X749883D01*
X749383Y899189D01*
Y905189D01*
X753883Y909689D01*
X767383D01*
X771383Y905689D01*
Y902689D01*
X768883Y900189D01*
X753383D01*
G37*
G36*
G01X838280Y243088D02*
G03X839060Y251200I-41823J8115D01*
G01Y274805D01*
G03X838362Y282483I-42603J-2D01*
G02X838842Y282945I394J72D01*
G01X843061Y282008D01*
X843062Y282009D01*
X847747Y280968D01*
X847748Y280969D01*
X852433Y279928D01*
X852972Y280271D01*
X864782Y277650D01*
X865152Y277067D01*
X869910Y276011D01*
X869912Y276007D01*
X874675Y274951D01*
X874676Y274950D01*
X877495Y274326D01*
X879452Y273891D01*
X879453D01*
X888984Y271779D01*
X889565Y272150D01*
X893863Y271196D01*
X894204Y270662D01*
X898620Y269680D01*
X899500Y268800D01*
Y266807D01*
X888064Y258214D01*
G02X887459Y258369I-240J320D01*
G03X857486Y246721I-14664J-6655D01*
G02X857182Y246204I-380J-124D01*
G01X838749Y242619D01*
G02X838280Y243088I-76J393D01*
G37*
G36*
G01X869146Y-16366D02*
X874142D01*
Y-144756D01*
X1124332D01*
Y-129755D01*
G03X1124166Y-100483I-6797J14598D01*
G02X1124143Y-99765I164J365D01*
G03X1131073Y-78479I-7543J14227D01*
G03X1128902Y-69373I-16073J980D01*
G03X1130414Y-53974I-13299J9080D01*
G03X1129800Y-50956I-16014J-1687D01*
G02X1130148Y-50441I383J117D01*
G03X1132135Y-50146I-1381J16144D01*
G03X1150788Y-51319I10157J12624D01*
G03X1157598Y-49300I-1089J16166D01*
G01X1173102D01*
Y-3937D01*
G02X1185039Y8000I11937J0D01*
G01X1194954D01*
Y23001D01*
X1196270Y24317D01*
X1212082D01*
X1229269Y41504D01*
Y94382D01*
X1219282Y104369D01*
X1215631D01*
X1215596Y104383D01*
G03X1209768Y105474I-5827J-15016D01*
G01X1199657D01*
G03X1189527Y116517I-15569J-4114D01*
G03X1162627Y106182I-10871J-11880D01*
G01X1162610Y106001D01*
X1140137D01*
Y151985D01*
G03X1148848Y157630I-3934J15615D01*
G03X1154677Y163763I-8348J13770D01*
G03X1158145Y169756I-11878J10873D01*
G02X1158741Y169972I381J-121D01*
G01X1277233Y94485D01*
X1285246Y92708D01*
G02X1285509Y92123I-86J-390D01*
G03X1302184Y68383I14060J-7851D01*
G03X1303953Y68218I2378J15926D01*
G03X1307807Y57545I16102J-218D01*
G03X1325602Y39924I16022J-1616D01*
G03X1333018Y40405I2694J15876D01*
G03X1346003Y47726I-518J16095D01*
G01X1362079D01*
Y55118D01*
G02X1365719Y63700I11937J0D01*
G01X1369674D01*
Y60533D01*
G03X1367075Y55118I4342J-5415D01*
G01Y3937D01*
G02X1366142Y3004I-933J0D01*
G01X1185039D01*
G03X1178098Y-3937I0J-6941D01*
G01Y-148819D01*
G02X1177165Y-149752I-933J0D01*
G01X870079D01*
G02X869146Y-148819I0J933D01*
G01Y-16366D01*
G37*
G36*
G01X922263Y38937D02*
X926795Y34405D01*
X926690Y34267D01*
G03X932628Y32111I2641J-1983D01*
G01X932638Y32300D01*
X951614D01*
X951624Y32111D01*
G03X957179Y29874I3297J173D01*
G02X957735Y29865I273J-292D01*
G01X959400Y28200D01*
Y9100D01*
X954300Y4000D01*
X907329D01*
X887197Y24132D01*
Y35883D01*
G03Y38877I-1749J1497D01*
G01Y44575D01*
X884534Y47238D01*
X869509D01*
X867948Y48799D01*
Y78271D01*
X874007Y84330D01*
X914957D01*
X922263Y77024D01*
Y38937D01*
G37*
G36*
G01X864432Y389800D02*
X848939D01*
X847052Y391687D01*
Y430345D01*
X848238Y431531D01*
X863840D01*
X865432Y429939D01*
Y390800D01*
X864432Y389800D01*
G37*
G36*
G01X869434D02*
Y431130D01*
X869834Y431531D01*
X885436D01*
X886622Y430345D01*
Y391687D01*
X884735Y389800D01*
X869434D01*
G37*
G36*
G01X885100Y681850D02*
X864950D01*
X863200Y683600D01*
Y694900D01*
X863900Y695600D01*
X885800D01*
X886800Y694600D01*
Y683550D01*
X885100Y681850D01*
G37*
G36*
G01X888659Y698400D02*
X887457Y699602D01*
X863300D01*
Y703200D01*
X877479Y725797D01*
X933553D01*
X935499Y723851D01*
G03X940336Y718976I6627J1739D01*
G01X940387Y718963D01*
X943651Y715699D01*
Y708335D01*
X941716Y706400D01*
X940905D01*
G02X940506Y706788I1J400D01*
G03X933904I-3301J-96D01*
G02X933505Y706400I-400J12D01*
G01X925800D01*
X917800Y698400D01*
X888659D01*
G37*
G36*
G01X975322Y1198255D02*
G03X965698Y1193256I2177J-15955D01*
G03X959316Y1190103I3765J-15657D01*
G03X952048Y1186232I3684J-15676D01*
G03X942864Y1165380I5823J-15013D01*
G03X943861Y1157783I16006J-1763D01*
G03X940797Y1136977I10534J-12180D01*
G02X940654Y1136414I-338J-214D01*
G03X929680Y1127634I20764J-37201D01*
G02X929000Y1127785I-297J267D01*
G01X878200Y1295220D01*
G02X878865Y1295619I383J116D01*
G01X951545Y1222939D01*
X951560Y1222910D01*
G03X958923Y1215561I14522J7186D01*
G01X975550Y1198934D01*
G02X975322Y1198255I-283J-283D01*
G37*
G36*
G01X942674Y1378207D02*
X908438Y1412443D01*
X875822D01*
G03X872393Y1412873I-1904J-1294D01*
G02X872119Y1412881I-133J150D01*
G01X869702Y1415298D01*
Y1424602D01*
X871500Y1426400D01*
X912370D01*
X936388Y1402382D01*
G03X945670Y1393093I25029J15728D01*
G01X945689Y1393081D01*
X951189Y1387581D01*
X977162D01*
X1019865Y1430284D01*
X1140984D01*
X1142900Y1432200D01*
X1144400D01*
X1150400Y1426200D01*
Y1422470D01*
X1147200Y1419270D01*
X1029470D01*
X1017102Y1406902D01*
X1016859D01*
X988165Y1378207D01*
X942674D01*
G37*
G36*
G01X1050744Y1237207D02*
Y1225344D01*
X1047900Y1222500D01*
X1045212D01*
X1031163Y1236549D01*
X994052D01*
X918075Y1312526D01*
G03X915947Y1315788I-14536J-7158D01*
G01X915900Y1315844D01*
Y1316900D01*
X917400Y1318400D01*
X1001706D01*
G03X1021627Y1308543I15129J5516D01*
G03X1033839Y1310538I3709J15673D01*
G03X1050150Y1310129I8504J13678D01*
G02X1050744Y1309779I194J-350D01*
G01Y1294902D01*
G03X1052775Y1287099I16006J0D01*
G01X1052800Y1287054D01*
Y1280100D01*
X1047482Y1274782D01*
X1047397Y1274784D01*
G03X1036856Y1246180I-396J-16098D01*
G03X1050744Y1237207I14443J7120D01*
G37*
G36*
G01X1063450Y-24416D02*
G03X1061972Y-24288I-2127J-15962D01*
G03X1057203Y-13217I-16099J-372D01*
G03X1041681Y-5698I-13690J-8479D01*
G03X1023800Y4191I-14964J-5948D01*
G03X1006956Y-3958I-2714J-15873D01*
G01X996288D01*
G03X974814Y4197I-20501J-21632D01*
G02X974401Y4597I-13J400D01*
G01Y34414D01*
X972027Y36788D01*
Y48032D01*
G03X970107Y55906I-17106J0D01*
G03X972027Y63780I-15186J7874D01*
G01Y98211D01*
X981297Y104015D01*
G03X985870Y108436I-8135J12991D01*
G01X986658Y109604D01*
X986793Y109572D01*
G03X1002300Y114198I3772J15658D01*
G03X1009671Y127730I-8736J13532D01*
G01Y137730D01*
G03X1000500Y152266I-16105J0D01*
G01X1000360Y152333D01*
X1016845Y237116D01*
X995049Y349257D01*
X994964Y349384D01*
X995120Y349497D01*
G03X974921Y374523I-9431J13053D01*
G01X974794Y374410D01*
X965674Y381742D01*
G02Y382365I251J311D01*
G03X972027Y395669I-10754J13304D01*
G01Y427165D01*
G03X970107Y435039I-17106J0D01*
G03X972027Y442913I-15186J7874D01*
G01Y534944D01*
G02X972471Y535342I400J0D01*
G03X999576Y547008I3315J29618D01*
G01X999636Y547088D01*
X1001885D01*
G02X1002284Y546652I1J-400D01*
G03X1028721Y532911I16038J-1445D01*
G02X1029315Y532824I259J-305D01*
G01X1060500Y484802D01*
Y477500D01*
X1056547Y473547D01*
X1056534Y473538D01*
G03X1051153Y466769I9452J-13037D01*
G02X1050613Y466563I-369J156D01*
G03X1027656Y449478I-6939J-14642D01*
G03X1027422Y447499I15844J-2877D01*
G03X1024332Y440882I12758J-9988D01*
G01X1021877D01*
Y433407D01*
X1018766Y430296D01*
Y385287D01*
X1026192Y377862D01*
X1026207Y377817D01*
G03X1050335Y369395I15293J5041D01*
G03X1054945Y371799I-5043J15293D01*
G01X1062101D01*
X1063800Y370100D01*
Y364529D01*
X1053341Y348111D01*
X1035235Y265973D01*
X1037640Y255102D01*
X1037644Y255099D01*
X1055879Y172857D01*
X1076354Y140712D01*
G03X1080335Y136502I12927J8236D01*
G01Y68307D01*
G02X1079874Y67912I-400J0D01*
G03X1061372Y50443I-2474J-15912D01*
G03X1061158Y42826I15533J-4248D01*
G03X1061190Y41581I16102J-209D01*
G03X1061033Y37662I15892J-2599D01*
G03X1061013Y37529I15914J-2461D01*
G02X1060741Y37372I-198J29D01*
G03X1066152Y10985I-5941J-14967D01*
G03X1073499Y6808I11353J11420D01*
G01Y-6314D01*
X1081098Y-13912D01*
G02X1080782Y-14593I-283J-282D01*
G03X1064607Y-24257I-1326J-16149D01*
G03X1063450Y-24416I1612J-16022D01*
G37*
G36*
G01X972027Y594976D02*
Y679497D01*
G02X972557Y679875I400J0D01*
G03X981347Y679397I5236J15228D01*
G01X981528Y679438D01*
X1015836Y566371D01*
G02X1015522Y565861I-383J-116D01*
G03X1005983Y560373I2777J-15862D01*
G02X1005281Y560688I-306J257D01*
G03X972471Y594578I-29495J4272D01*
G02X972027Y594976I-44J398D01*
G37*
G36*
G01X1009333Y1175297D02*
G03X1018425Y1180057I-2534J15903D01*
G03X1027620Y1183717I-1070J16068D01*
G01X1027760Y1183833D01*
X1033980Y1177614D01*
X1033880Y1177475D01*
G03X1038677Y1154155I13020J-9475D01*
G02X1038813Y1153601I-204J-344D01*
G03X1036936Y1149199I13710J-8447D01*
G02X1036196Y1149111I-387J100D01*
G03X1011166Y1153447I-14205J-7585D01*
G03X1009017Y1152995I2232J-15947D01*
G03X999424Y1152949I-4723J-15395D01*
G03X993453Y1153524I-4502J-15461D01*
G02X993028Y1154019I-37J398D01*
G03X989461Y1168569I-15628J3881D01*
G02X989582Y1169192I300J265D01*
G03X989869Y1169339I-7197J14405D01*
G03X1009333Y1175297I6080J14911D01*
G37*
G36*
G01X991000Y1453500D02*
X985165Y1459335D01*
X985156Y1459347D01*
G03X979032Y1465471I-23739J-17615D01*
G01X979020Y1465480D01*
X967221Y1477279D01*
Y1506547D01*
X968452Y1507778D01*
X976183D01*
X977253Y1506708D01*
Y1478217D01*
X993282Y1462189D01*
Y1462069D01*
X995262Y1460088D01*
X995382D01*
X995940Y1459530D01*
X1078910D01*
X1079500Y1458940D01*
Y1454500D01*
X1078500Y1453500D01*
X991000D01*
G37*
G36*
G01X969857Y1629995D02*
X968763Y1631089D01*
Y1649558D01*
X970834Y1651630D01*
X989792D01*
X992363Y1649058D01*
Y1631334D01*
X991024Y1629995D01*
X969857D01*
G37*
G36*
G01X1057382Y389000D02*
X1036268D01*
X1033767Y391501D01*
Y424082D01*
X1036895Y427210D01*
X1048595D01*
X1052025Y423780D01*
Y415798D01*
X1059665Y408158D01*
Y391283D01*
X1057382Y389000D01*
G37*
G36*
G01X1037385Y820200D02*
X1037444Y820112D01*
G03X1048053Y813290I13318J9051D01*
G03X1068640Y820528I6366J14791D01*
G01X1068654Y820554D01*
X1070100Y822000D01*
X1075019D01*
G03X1099651Y823756I11580J11199D01*
G03X1076249Y845544I-10350J12345D01*
G03X1074647Y844000I10352J-12344D01*
G01X1069878D01*
G03X1051295Y855290I-15459J-4507D01*
G03X1047181Y856376I-6131J-14890D01*
G03X1046218Y859128I-15619J-3921D01*
G01X1046200Y859167D01*
Y863208D01*
G03X1052289Y885015I-7985J13983D01*
G02X1052652Y885609I350J194D01*
G03X1059960Y916318I548J16094D01*
G03X1060154Y925858I-15280J5083D01*
G03X1060193Y927730I-16053J1271D01*
G03X1064587Y928807I-1623J16122D01*
G03X1068385Y926994I8820J13592D01*
G03X1084229Y916081I15247J5179D01*
G01X1084316Y916084D01*
X1086300Y914100D01*
Y912531D01*
X1086281Y912491D01*
G03X1089815Y893882I14566J-6874D01*
G03X1100930Y886693I13532J8735D01*
G03X1102166Y883606I15490J4411D01*
G03X1100053Y875632I13993J-7975D01*
G01Y870630D01*
G03X1107424Y857098I16107J0D01*
G03X1135265Y868130I11735J11032D01*
G01Y878130D01*
G03X1134514Y882991I-16107J0D01*
G03X1135525Y888607I-15095J5616D01*
G01Y898607D01*
G03X1124708Y913820I-16106J0D01*
G03X1110847Y921723I-13861J-8204D01*
G01X1100847D01*
G03X1099622Y921676I5J-16106D01*
G01X1099531Y921669D01*
X1097700Y923500D01*
Y924335D01*
X1097725Y924380D01*
G03X1099227Y928157I-14092J7791D01*
G03X1100440Y928111I1216J16060D01*
G01X1110447D01*
G03X1121479Y955952I0J16106D01*
G03X1107947Y963323I-13532J-8736D01*
G01X1102947D01*
G03X1089415Y955952I0J-16107D01*
G03X1086690Y952593I11032J-11735D01*
G02X1086037Y952551I-341J208D01*
G03X1067392Y957444I-12629J-10152D01*
G03X1049766Y957454I-8821J-13592D01*
G02X1049489Y957513I-109J168D01*
G03X1039000Y964611I-13542J-8713D01*
G01Y979016D01*
X1039176Y979037D01*
G03X1046647Y981928I-1893J15991D01*
G03X1055912Y989814I-5031J15297D01*
G01X1055926Y989841D01*
X1056316Y990231D01*
X1056395Y990233D01*
G03X1061098Y991088I-515J16195D01*
G01X1074314D01*
G02X1074711Y990638I0J-400D01*
G03X1091089Y972086I16378J-2047D01*
G01X1133609D01*
G03X1138743Y972905I-1J16506D01*
G02X1139267Y972524I124J-380D01*
G01Y957480D01*
G03X1184167Y914939I42603J0D01*
G01X1184256Y914944D01*
X1188600Y910600D01*
Y903559D01*
X1176380Y848427D01*
X1197911Y751288D01*
G02X1197521Y750801I-390J-87D01*
G01X1181686D01*
X1176899Y746014D01*
X1176793Y746038D01*
G03X1173368Y746406I-3423J-15738D01*
G01X1169767D01*
G03X1161501Y744123I0J-16106D01*
G01X1161382Y744051D01*
X1133583Y766398D01*
X1108348Y774475D01*
X1088435Y768123D01*
X1085511Y767182D01*
X1057921Y744986D01*
X1057427Y743112D01*
X1057144Y742885D01*
Y742042D01*
X1055676Y736476D01*
X1052200Y733000D01*
X1049249D01*
X1048800Y734481D01*
X1048238Y734781D01*
X1046116Y741775D01*
X1046416Y742336D01*
X1042164Y756353D01*
X1042163Y756354D01*
X1040772Y760940D01*
X1040211Y761240D01*
X1023600Y815989D01*
Y817800D01*
X1024922Y819122D01*
G03X1035165Y820182I3551J15707D01*
G01X1035204Y820200D01*
X1037385D01*
G37*
G36*
G01X1017194Y1049946D02*
X1012492D01*
G03X1009828Y1049724I1J-16106D01*
G03X1002224Y1048832I-1980J-15981D01*
G03X996149Y1049840I-5625J-15089D01*
G02X995815Y1050476I-11J400D01*
G03X1004021Y1075613I-34397J25137D01*
G01Y1083267D01*
G02X1004726Y1083526I400J0D01*
G03X1019774Y1078088I12274J10424D01*
G02X1020149Y1077437I69J-394D01*
G03X1032500Y1050994I12351J-10337D01*
G01X1037000D01*
G03X1052170Y1061691I0J16105D01*
G03X1053870Y1061578I1917J15989D01*
G03X1069000Y1050994I15130J5522D01*
G01X1082501D01*
G03X1083542Y1051028I-5J16106D01*
G02X1083839Y1050334I26J-399D01*
G03X1079070Y1042425I11186J-12137D01*
G03X1074712Y1029051I12019J-11314D01*
G02X1074315Y1028601I-397J-50D01*
G01X1070692D01*
X1070661Y1028612D01*
G03X1067236Y1029368I-5184J-15351D01*
G03X1049838Y1037426I-14137J-7711D01*
G03X1035703Y1031137I-1326J-16048D01*
G02X1035028Y1031199I-318J242D01*
G03X1033300Y1033909I-14374J-7259D01*
G03X1017194Y1049946I-16106J-69D01*
G37*
G36*
G01X1003500Y1432500D02*
X994500Y1441500D01*
Y1449500D01*
X997000Y1452000D01*
X1079000D01*
X1081000Y1454000D01*
Y1459910D01*
X1079620Y1461290D01*
X995760D01*
X994483Y1462567D01*
Y1484633D01*
X995360Y1485510D01*
X1080230D01*
X1082000Y1487280D01*
Y1609593D01*
X1086719Y1614312D01*
X1137982D01*
X1145983Y1606311D01*
Y1459747D01*
X1145868Y1459632D01*
Y1442768D01*
X1136952Y1433852D01*
G02X1136289Y1434012I-282J283D01*
G03X1131823Y1432959I-2189J-712D01*
G02X1131428Y1432500I-395J-59D01*
G01X1003500D01*
G37*
G36*
G01X1079580Y1487500D02*
X994890D01*
X994090Y1488300D01*
Y1529090D01*
X1001108Y1536108D01*
X1078364D01*
X1080573Y1533899D01*
Y1488493D01*
X1079580Y1487500D01*
G37*
G36*
G01X1065330Y386800D02*
X1062707Y389423D01*
Y412513D01*
X1060041Y415179D01*
Y426651D01*
X1061457Y428067D01*
X1076723D01*
X1094260Y410530D01*
X1094274Y410481D01*
G03X1100601Y410458I3167J936D01*
G01X1100644Y410600D01*
X1102804D01*
G02X1103075Y409906I0J-400D01*
G03X1107555I2240J-2426D01*
G02X1107826Y410600I271J294D01*
G01X1112646D01*
G02X1112917Y409906I0J-400D01*
G03X1117397I2240J-2426D01*
G02X1117668Y410600I271J294D01*
G01X1119828D01*
X1119871Y410458D01*
G03X1126191I3160J959D01*
G01X1126234Y410600D01*
X1129200D01*
X1132400Y407400D01*
Y389200D01*
X1130000Y386800D01*
X1065330D01*
G37*
G36*
G01X1562992Y3004D02*
G02X1562059Y3937I0J933D01*
G01Y55118D01*
G03X1560274Y59765I-6941J0D01*
G01Y80626D01*
G03X1560046Y80618I426J-15396D01*
G03X1549952Y79312I-3046J-16118D01*
G02X1549380Y79673I-172J361D01*
G01Y80974D01*
X1549413Y81024D01*
G03X1552316Y90283I-14465J9620D01*
G03X1552320Y90644I-15323J350D01*
G01Y146470D01*
G02X1552798Y146862I400J0D01*
G03X1555925Y146555I3130J15799D01*
G01X1560434D01*
G03X1562237Y146657I-7J16106D01*
G01X1562248Y146658D01*
X1574547D01*
G02X1574819Y145965I0J-400D01*
G03X1596695I10938J-11818D01*
G02X1596967Y146658I272J293D01*
G01X1639011D01*
G03X1645881Y139099I15320J7023D01*
G03X1677268Y146152I15863J2772D01*
G02X1677653Y146658I385J106D01*
G01X1678315D01*
X1678326Y146657D01*
G03X1680129Y146555I1810J16004D01*
G01X1684647D01*
G03X1686450Y146657I-7J16106D01*
G01X1686461Y146658D01*
X1763223D01*
G03X1770093Y139099I15320J7023D01*
G03X1801455Y146238I15863J2771D01*
G02X1801901Y146742I385J109D01*
G03X1804346Y146555I2447J15919D01*
G01X1808859D01*
G03X1810662Y146657I-7J16106D01*
G01X1810673Y146658D01*
X1826206D01*
G03X1853234Y142472I14815J6310D01*
G01X1860775D01*
G03X1872090Y147160I-1J16002D01*
G01X1876324Y151393D01*
X1876437Y151360D01*
G03X1885585Y151448I4426J15382D01*
G02X1886098Y151127I118J-382D01*
G03X1894306Y139099I16658J2553D01*
G03X1911832Y125853I15863J2771D01*
G01X1911842Y125854D01*
X1926843D01*
Y1235642D01*
X1911842D01*
X1911832Y1235643D01*
G03X1911753Y1235651I-1662J-16017D01*
G01X1908585D01*
G03X1894522Y1223430I1584J-16025D01*
G03X1891292Y1221239I8234J-15615D01*
G03X1873517Y1197133I-4123J-15566D01*
G02X1873367Y1196568I-339J-212D01*
G03X1865492Y1177930I7603J-14195D01*
G01X1865500Y1177903D01*
Y1169794D01*
G02X1865082Y1169394I-400J0D01*
G03X1857419Y1167842I-731J-16086D01*
G03X1843081Y1167561I-6886J-14556D01*
G03X1839433Y1167715I-2499J-15908D01*
G03X1826810Y1164836I-3033J-15815D01*
G02X1826191Y1165279I-238J322D01*
G03X1821000Y1182675I-15341J4895D01*
G01Y1193551D01*
G03X1809850Y1221279I-11150J11622D01*
G01X1801975D01*
X1801955Y1221456D01*
G03X1799876Y1227723I-15999J-1829D01*
G02X1800200Y1228323I346J201D01*
G03X1840536Y1270866I-2267J42543D01*
G01Y1294466D01*
G03X1755330I-42603J0D01*
G01Y1270866D01*
G03X1777043Y1233736I42603J0D01*
G02X1777068Y1233054I-196J-349D01*
G03X1770309Y1223430I8888J-13428D01*
G03X1768703Y1222471I8235J-15615D01*
G03X1740491Y1208027I-12803J-9767D01*
G01X1740500Y1207999D01*
Y1200545D01*
G02X1740020Y1200153I-400J0D01*
G01X1715987Y1205042D01*
G02X1715747Y1205673I80J392D01*
G03X1718783Y1217550I-12909J9626D01*
G03X1720810Y1218963I-8168J13878D01*
G03X1704856Y1246466I-5761J15037D01*
G03X1694672Y1229179I5761J-15037D01*
G03X1687827Y1221130I8166J-13879D01*
G03X1685645Y1221279I-2186J-15957D01*
G01X1677763D01*
X1677743Y1221456D01*
G03X1646097Y1223430I-15999J-1830D01*
G03X1641784Y1220232I8235J-15614D01*
G01X1641708Y1220155D01*
X1624217Y1223714D01*
G02X1624033Y1224406I80J392D01*
G03X1598887Y1229522I-10633J12094D01*
G02X1598447Y1228957I-360J-173D01*
G01X1572860Y1234164D01*
G02X1572726Y1234893I80J392D01*
G03X1592504Y1270866I-22826J35973D01*
G01Y1294466D01*
G03X1507298I-42603J0D01*
G01Y1270866D01*
G03X1514835Y1246671I42603J0D01*
G02X1514426Y1246052I-330J-227D01*
G01X1487057Y1251621D01*
X1487012Y1251690D01*
G03X1467604Y1257722I-13412J-8913D01*
G01X1467509Y1257684D01*
X1393000Y1305159D01*
Y1318030D01*
G03X1380304Y1345633I-11200J11570D01*
G02X1379911Y1346212I-36J398D01*
G03X1381564Y1351802I-14361J7286D01*
G01X1381583Y1351981D01*
X1381589D01*
G03X1374637Y1366803I-16038J1519D01*
G01X1356465D01*
G03X1349531Y1351802I9086J-13303D01*
G01X1349537D01*
X1349558Y1351625D01*
G03X1356426Y1340232I15993J1875D01*
G02X1356522Y1339666I-227J-330D01*
G03X1353427Y1331078I13078J-9565D01*
G02X1352813Y1330765I-399J24D01*
G01X1331910Y1344083D01*
X1297090Y1351802D01*
Y1366668D01*
X1296955Y1366803D01*
X1168110D01*
G02X1156173Y1378740I0J11937D01*
G01Y1468504D01*
G02X1168110Y1480441I11937J0D01*
G01X1212472D01*
Y1611306D01*
X1197471D01*
X1197436Y1611320D01*
G03X1161575Y1609102I-15546J-39666D01*
G02X1160984Y1609453I-191J351D01*
G01Y1612525D01*
X1144196Y1629313D01*
X1134710D01*
G02X1134311Y1629727I1J400D01*
G03X1134115Y1634363I-29784J1063D01*
G01X1134094Y1634384D01*
Y1634534D01*
G03X1133993Y1635259I-29566J-3749D01*
G01X1133991Y1635274D01*
Y1650268D01*
X1071589D01*
Y1655264D01*
X1216535D01*
G02X1217468Y1654331I0J-933D01*
G01Y1476378D01*
G02X1216535Y1475445I-933J0D01*
G01X1168110D01*
G03X1161169Y1468504I0J-6941D01*
G01Y1378740D01*
G03X1168110Y1371799I6941J0D01*
G01X1930906D01*
G02X1931839Y1370866I0J-933D01*
G01Y3937D01*
G02X1930906Y3004I-933J0D01*
G01X1562992D01*
G37*
G36*
G01X1091400Y-3000D02*
X1088500Y-100D01*
Y31400D01*
X1093700Y36600D01*
X1101613D01*
G02X1102013Y36202I0J-400D01*
G03X1108617I3302J19D01*
G02X1109017Y36600I400J-2D01*
G01X1111455D01*
G02X1111855Y36202I0J-400D01*
G03X1118459I3302J19D01*
G02X1118859Y36600I400J-2D01*
G01X1129100D01*
X1141500Y49000D01*
Y89000D01*
X1143500Y91000D01*
X1188500D01*
X1190130Y89370D01*
X1190066Y89306D01*
Y39328D01*
X1147738Y-3000D01*
X1091400D01*
G37*
G36*
G01X1223758Y528145D02*
G03X1242150Y502653I12038J-10695D01*
G03X1250604Y500615I7861J14054D01*
G03X1267609Y492198I14275J7453D01*
G01X1267735Y492220D01*
X1271703Y486450D01*
X1272327Y486335D01*
X1294636Y453883D01*
X1294509Y453200D01*
X1300031Y445170D01*
Y445168D01*
X1302629Y441389D01*
X1305563Y437119D01*
X1305566Y437118D01*
X1308338Y433088D01*
X1309018Y432962D01*
X1310050Y431461D01*
G02X1309647Y430841I-330J-227D01*
G03X1259267Y388954I-7777J-41887D01*
G01Y365354D01*
G03X1260564Y354924I42603J2D01*
G02X1259946Y354498I-388J-99D01*
G01X1248370Y362619D01*
X1147401Y385001D01*
Y413614D01*
X1140137Y420878D01*
Y427165D01*
G03X1138217Y435039I-17106J0D01*
G03X1140137Y442913I-15186J7874D01*
G01Y513937D01*
X1142800Y516600D01*
X1149366D01*
X1149426Y516530D01*
G03X1224493Y544117I32464J27587D01*
G01Y547093D01*
X1225600Y548200D01*
X1229799D01*
X1234200Y541797D01*
Y539421D01*
G03X1223758Y528145I5162J-15253D01*
G37*
G36*
G01X1147454Y592800D02*
X1143100D01*
X1140137Y595763D01*
Y668037D01*
X1142100Y670000D01*
X1146070D01*
X1149126Y665555D01*
X1149000Y664877D01*
X1151764Y660854D01*
X1151763Y660851D01*
X1154354Y657083D01*
X1157288Y652813D01*
X1157290Y652812D01*
X1159883Y649040D01*
X1162824Y644759D01*
X1162827D01*
X1165592Y640739D01*
X1166272Y640613D01*
X1170607Y634305D01*
G02X1170437Y633711I-329J-227D01*
G03X1165401Y607595I6398J-14777D01*
G02X1165273Y606945I-284J-282D01*
G03X1147514Y592882I16617J-39229D01*
G01X1147454Y592800D01*
G37*
G36*
G01X1205868Y39318D02*
X1194668D01*
X1194068Y39918D01*
Y87649D01*
X1195787Y89368D01*
X1213068D01*
X1214268Y88168D01*
Y47718D01*
X1205868Y39318D01*
G37*
G36*
G01X1197100Y712200D02*
X1187100D01*
X1185300Y714000D01*
Y733200D01*
X1187900Y735800D01*
X1196100D01*
X1198700Y733200D01*
Y713800D01*
X1197100Y712200D01*
G37*
G36*
G01X1258768Y1285206D02*
G03X1251886Y1285437I-3969J-15606D01*
G01X1251807Y1285422D01*
X1221381Y1305563D01*
X1210800Y1322177D01*
Y1326300D01*
X1215635Y1331135D01*
X1266905Y1319770D01*
G02X1267144Y1319147I-87J-391D01*
G03X1259267Y1294468I34726J-24680D01*
G01Y1285594D01*
G02X1258768Y1285206I-400J0D01*
G37*
G36*
G01X1370800Y308609D02*
G03X1364693Y305795I3537J-15710D01*
G03X1346031Y301000I-6120J-14895D01*
G01X1336209D01*
X1328755Y306229D01*
X1328739Y306305D01*
G03X1310844Y318858I-15739J-3405D01*
G01X1310767Y318847D01*
X1308100Y320718D01*
Y322700D01*
X1308703Y323303D01*
X1308766Y323313D01*
G03X1344473Y365354I-6896J42041D01*
G01Y371173D01*
X1346000Y372700D01*
X1350445D01*
X1375427Y336358D01*
X1375269Y336244D01*
G03X1370773Y315138I9444J-13044D01*
G01X1370800Y315092D01*
Y308609D01*
G37*
G36*
G01X1307496Y599311D02*
X1312009D01*
G03X1313812Y599413I-7J16106D01*
G01X1313823Y599414D01*
X1339399D01*
Y580386D01*
X1339855Y579930D01*
Y575047D01*
X1342983D01*
X1343085Y574800D01*
X1342999Y574714D01*
Y549682D01*
G03X1341493Y545300I14317J-7370D01*
G03X1337247Y543336I4566J-15442D01*
G01X1337083Y543229D01*
X1304641Y590386D01*
X1304665Y590475D01*
G03X1304605Y598994I-15559J4150D01*
G02X1305051Y599498I385J109D01*
G03X1307496Y599311I2447J15919D01*
G37*
G36*
G01X1512716Y1204843D02*
X1512740Y1204709D01*
G03X1519695Y1193568I17377J3107D01*
G02X1519727Y1192948I-236J-323D01*
G03X1514750Y1184225I10803J-11945D01*
G02X1514112Y1183990I-392J80D01*
G03X1489391Y1177625I-9912J-12690D01*
G01X1489313Y1177441D01*
X1462593Y1188739D01*
X1450000Y1191531D01*
Y1195381D01*
X1450041Y1195434D01*
G03X1437213Y1221279I-12828J9739D01*
G01X1429338D01*
X1429318Y1221456D01*
G03X1403351Y1232273I-15999J-1830D01*
G02X1402749Y1232401I-248J314D01*
G03X1386722Y1208895I-14249J-7501D01*
G01X1386900Y1208875D01*
Y1207800D01*
X1385034Y1205934D01*
X1365278Y1210313D01*
X1326895Y1235720D01*
G02X1326881Y1236377I221J333D01*
G03X1344473Y1270866I-25012J34489D01*
G01Y1275173D01*
X1348100Y1278800D01*
X1358004D01*
X1359223Y1278015D01*
X1359224Y1278010D01*
X1364066Y1274896D01*
X1367575Y1272637D01*
X1367576D01*
X1374638Y1268090D01*
X1375470Y1268270D01*
X1451045Y1219623D01*
X1451058Y1219533D01*
G03X1479391Y1211516I15942J2267D01*
G01X1479467Y1211608D01*
X1512716Y1204843D01*
G37*
G36*
G01X1825890Y595328D02*
X1828976D01*
X1829035Y595264D01*
G03X1852328Y594900I11820J10936D01*
G01X1864200D01*
X1870026Y589074D01*
Y585327D01*
X1896866Y558486D01*
Y504559D01*
G02X1896442Y504160I-400J0D01*
G03X1882559Y501634I-1758J-29751D01*
G01X1882520Y501617D01*
X1879368D01*
G02X1879001Y502176I0J400D01*
G03X1864232Y524706I-14769J6424D01*
G01X1863414D01*
X1863358Y524814D01*
G03X1843314Y532484I-14313J-7379D01*
G03X1843102Y532453I2224J-15949D01*
G03X1827569Y532937I-8206J-13856D01*
G03X1837684Y502482I3761J-15658D01*
G03X1845350Y500434I7861J14054D01*
G03X1859232Y492494I13882J8165D01*
G01X1864234D01*
G03X1867224Y492774I0J16106D01*
G02X1867698Y492381I74J-393D01*
G01Y487055D01*
X1867679Y487015D01*
G03X1896442Y444658I27005J-12606D01*
G02X1896866Y444259I24J-399D01*
G01Y323189D01*
G03X1894522Y317918I13304J-9073D01*
G03X1887394Y311001I8233J-15616D01*
G03X1868146Y286602I-6306J-14817D01*
G03X1886990Y261926I12823J-9741D01*
G02X1887528Y261651I150J-371D01*
G03X1890544Y255492I15641J3841D01*
G03X1887063Y245492I12625J-10001D01*
G01Y235492D01*
G03X1888161Y229647I16106J0D01*
G03X1882575Y218082I10507J-12207D01*
G02X1882139Y217700I-399J16D01*
G03X1880669Y217767I-1468J-16039D01*
G01X1871491D01*
G03X1870943Y219181I-15272J-5106D01*
G02X1871160Y219714I366J162D01*
G03X1880010Y240911I-5991J14947D01*
G03X1856571Y260777I-14841J6250D01*
G02X1855989Y260958I-214J338D01*
G03X1833475Y268806I-14820J-6297D01*
G01X1833430Y268782D01*
X1826417D01*
G03X1817140Y279485I-15567J-4121D01*
G01Y285299D01*
G03X1809850Y315767I-7290J14362D01*
G01X1801975D01*
X1801955Y315944D01*
G03X1799876Y322211I-15999J-1829D01*
G02X1800200Y322811I346J201D01*
G03X1840536Y365354I-2267J42543D01*
G01Y388954D01*
G03X1755330I-42603J0D01*
G01Y365354D01*
G03X1777043Y328224I42603J0D01*
G02X1777068Y327542I-196J-349D01*
G03X1770309Y317918I8888J-13428D01*
G03X1768120Y288056I8234J-15615D01*
G02X1768152Y287436I-236J-323D01*
G03X1762922Y277013I10803J-11944D01*
G01X1762905Y276832D01*
X1758473D01*
X1758416Y276884D01*
G03X1734563Y255479I-10866J-11885D01*
G03X1733618Y254356I11836J-10919D01*
G01X1733521Y254229D01*
X1712308Y263970D01*
Y266544D01*
X1702231Y268685D01*
X1702199Y268804D01*
G03X1695895Y277837I-15561J-4143D01*
G01Y287243D01*
G03X1685638Y315767I-10257J12418D01*
G01X1677763D01*
X1677743Y315944D01*
G03X1646097Y317918I-15999J-1830D01*
G03X1641711Y289960I8234J-15615D01*
G02X1641691Y289381I-286J-280D01*
G03X1640792Y288517I10701J-12034D01*
G01X1640677Y288398D01*
X1575505Y330631D01*
G02X1575483Y331287I218J336D01*
G03X1592504Y365354I-25582J34067D01*
G01Y388954D01*
G03X1575223Y423215I-42603J0D01*
G02X1575292Y423900I237J322D01*
G03X1563602Y453840I-6792J14600D01*
G01X1400198D01*
G03X1398322Y454317I-4899J-15340D01*
G01X1398241Y454332D01*
X1371702Y492909D01*
G02X1371858Y493497I329J227D01*
G03X1380757Y510731I-6976J14517D01*
G02X1381151Y511198I394J67D01*
G01X1394371D01*
X1397028Y513854D01*
X1401734D01*
G03X1403090Y512359I12582J10050D01*
G03X1425211Y502366I15417J4648D01*
G03X1433414Y498994I9988J12634D01*
G02X1433762Y498521I-45J-397D01*
G03X1451388Y479481I15814J-3039D01*
G03X1471980Y477271I11612J11157D01*
G03X1497705Y493197I9958J12655D01*
G03X1505797Y500503I-6110J14902D01*
G03X1523068Y506975I4003J15597D01*
G03X1526908Y528150I-9868J12725D01*
G02X1527249Y528760I341J210D01*
G01X1542804D01*
G03X1553207Y528749I5218J15340D01*
G01X1553238Y528760D01*
X1563602D01*
X1563631Y528751D01*
G03X1570074Y528074I4870J15349D01*
G02X1570426Y527427I39J-398D01*
G03X1589384Y502608I12604J-10022D01*
G03X1596849Y500564I7861J14054D01*
G03X1610807Y492494I13958J8036D01*
G01X1615807D01*
G03Y524706I0J16106D01*
G01X1615177D01*
X1615121Y524816D01*
G03X1595014Y532610I-14376J-7255D01*
G03X1594802Y532579I2224J-15949D01*
G03X1582081Y534180I-8205J-13856D01*
G02X1581642Y534796I-113J384D01*
G03X1584098Y548101I-13142J9305D01*
G03X1563669Y564009I-16098J399D01*
G01X1563643Y564002D01*
X1559526D01*
X1559498Y564011D01*
G03X1550100Y564002I-4684J-15511D01*
G01X1522127D01*
G03X1507714Y569463I-12216J-10491D01*
G03X1495042Y576493I-13314J-9063D01*
G02X1494662Y576946I16J400D01*
G03X1478700Y595206I-15962J2153D01*
G01X1477624D01*
X1477564Y595286D01*
G03X1477047Y595938I-12872J-9676D01*
G01X1477000Y595993D01*
Y597100D01*
X1479314Y599414D01*
X1514798D01*
G03X1521668Y591855I15320J7023D01*
G03X1553632Y594891I15863J2770D01*
G01Y595094D01*
X1556105D01*
G03X1567041Y599414I0J16002D01*
G01X1639011D01*
G03X1645881Y591855I15320J7023D01*
G03X1677763Y596273I15863J2770D01*
G02X1678160Y596714I398J41D01*
G01X1680710D01*
X1716133Y561292D01*
X1791057D01*
X1820165Y590400D01*
G03X1823594Y595494I-11314J11317D01*
G03X1825890Y595328I2299J15837D01*
G37*
G36*
G01X1396900Y545900D02*
X1359600D01*
X1358000Y547500D01*
Y568500D01*
X1359800Y570300D01*
X1378800D01*
X1380000Y571500D01*
Y574500D01*
X1381000Y575500D01*
X1389000D01*
X1389500Y575000D01*
Y571000D01*
X1390000Y570500D01*
X1396500D01*
X1398000Y569000D01*
Y547000D01*
X1396900Y545900D01*
G37*
G36*
G01X1364000Y586000D02*
X1355000D01*
X1354400Y586600D01*
Y602600D01*
X1355400Y603600D01*
X1363800D01*
X1364700Y602700D01*
Y586700D01*
X1364000Y586000D01*
G37*
G36*
G01X1369000Y577500D02*
X1368000Y578500D01*
Y584341D01*
X1368702Y585043D01*
Y601702D01*
X1370500Y603500D01*
X1389844D01*
X1392252Y601092D01*
Y585793D01*
X1389500Y583041D01*
Y578000D01*
X1389000Y577500D01*
X1369000D01*
G37*
G36*
G01X1413856Y770821D02*
G03X1384583Y775394I-15611J-3951D01*
G01X1384525Y775300D01*
X1382628D01*
X1382578Y775334D01*
G03X1381548Y775973I-9051J-13439D01*
G01X1381471Y776017D01*
X1366778Y842278D01*
X1369900Y845400D01*
X1372812D01*
X1420500Y770565D01*
Y768371D01*
X1420330Y768345D01*
G03X1418080Y767842I2380J-15929D01*
G03X1413856Y770821I-12177J-12781D01*
G37*
G36*
G01X1369635Y985799D02*
G03X1365246Y981799I8466J-13698D01*
G02X1364656Y981745I-320J241D01*
G03X1350008Y985545I-10893J-11859D01*
G03X1344284Y984946I-1213J-16057D01*
G03X1342503Y985402I-4878J-15346D01*
G01X1342421Y985418D01*
X1334800Y996933D01*
Y1000500D01*
X1337815Y1003515D01*
G02X1338382Y1003514I283J-283D01*
G03X1350978Y998778I11447J11326D01*
G01X1351046Y998783D01*
X1369645Y986473D01*
G02X1369635Y985799I-220J-334D01*
G37*
G36*
G01X1500000Y990500D02*
X1500010Y990595D01*
G03X1495666Y1003415I-16010J1721D01*
G03X1491624Y1008281I-14167J-7656D01*
G03X1493989Y1020299I-13430J8885D01*
G03X1465734Y1027367I-12460J10201D01*
G03X1462107Y1017880I12460J-10201D01*
G02X1461467Y1017578I-400J18D01*
G03X1464703Y995066I-9667J-12878D01*
G02X1465423Y994849I321J-239D01*
G03X1468859Y985782I16077J908D01*
G02X1468654Y985149I-314J-248D01*
G03X1467688Y984845I4349J-15505D01*
G03X1462215Y985307I-4071J-15580D01*
G03X1444101Y975723I-3248J-15772D01*
G02X1443511Y975543I-369J154D01*
G01X1400865Y1003770D01*
X1400858Y1003868D01*
G03X1379632Y1017917I-16058J-1202D01*
G01X1379539Y1017885D01*
X1378797Y1018376D01*
G02X1378691Y1018941I220J334D01*
G03X1371620Y1043166I-13140J9309D01*
G02X1371442Y1043764I151J370D01*
G03X1375016Y1050398I-27742J19226D01*
G01X1391530D01*
G03X1397456Y1044611I14377J8794D01*
G03X1429344Y1045802I15863J2771D01*
G01X1429362Y1045982D01*
X1430025D01*
G03X1438289Y1048282I-2J16003D01*
G03X1458731Y1052170I7925J14018D01*
G01X1514798D01*
G03X1521668Y1044611I15320J7023D01*
G03X1553608Y1046473I15863J2771D01*
G01X1553619Y1046662D01*
X1554919D01*
G03X1561966Y1048298I-2J16002D01*
G03X1583180Y1052170I8459J13702D01*
G01X1639011D01*
G03X1645881Y1044611I15320J7023D01*
G03X1665190Y1031652I15863J2771D01*
G02X1665635Y1031085I86J-391D01*
G03X1663990Y1023551I14452J-7102D01*
G03X1669531Y993275I7432J-14285D01*
G01X1669707Y993254D01*
Y977249D01*
G03X1660978Y953739I5107J-15272D01*
G03X1668889Y940757I16078J896D01*
G03X1681112Y936337I11122J11645D01*
G02X1681405Y935639I27J-399D01*
G03X1690350Y907592I10695J-12039D01*
G02X1690638Y906971I-44J-398D01*
G03X1688967Y903746I13371J-8973D01*
G01X1688907Y903588D01*
X1646101Y912115D01*
G02X1645942Y912829I78J392D01*
G03X1649647Y934956I-9542J12971D01*
G03X1629714Y951927I-16047J1344D01*
G02X1629283Y952534I-96J388D01*
G03X1631782Y959302I-13476J8821D01*
G03X1620175Y988587I-2688J15877D01*
G03X1605423Y985744I-4681J-15408D01*
G03X1598433Y985629I-3236J-15774D01*
G03X1591901Y984771I-1213J-16057D01*
G03X1588197Y985290I-4071J-15580D01*
G03X1582947Y990456I-13620J-8591D01*
G02X1583088Y991192I208J342D01*
G03X1596189Y1003999I-2707J15874D01*
G02X1596723Y1004297I393J-76D01*
G03X1618317Y1016924I5677J15069D01*
G03X1604142Y1035374I1742J16008D01*
G03X1586592Y1022433I-1742J-16008D01*
G02X1586058Y1022135I-393J76D01*
G03X1572010Y993310I-5676J-15069D01*
G02X1571870Y992574I-208J-342D01*
G03X1569163Y961534I2706J-15874D01*
G03X1584581Y953419I14017J7927D01*
G03X1593149Y953992I3248J15772D01*
G03X1596760Y953476I4069J15580D01*
G03X1610807Y945249I14047J7879D01*
G01X1615807D01*
G03X1619694Y945725I0J16107D01*
G02X1620126Y945118I97J-388D01*
G03X1617768Y933355I13474J-8819D01*
G02X1617395Y932882I-393J-73D01*
G03X1609639Y930439I803J-16083D01*
G03X1596512Y925477I-1439J-16039D01*
G03X1578521Y925634I-9112J-13277D01*
G01X1578453Y925589D01*
X1536136Y934018D01*
X1536096Y934117D01*
G03X1515738Y943148I-14896J-6117D01*
G03X1506500Y946492I-9839J-12748D01*
G01Y952379D01*
G03X1506584Y983963I-3106J15800D01*
G01X1506525Y983975D01*
X1500000Y990500D01*
G37*
G36*
G01X1492219Y631420D02*
X1466408D01*
G03X1464231Y636566I-15694J-3606D01*
G02X1464425Y637158I336J218D01*
G03X1474819Y652217I-5712J15059D01*
G01Y668417D01*
G03X1468291Y681366I-16107J0D01*
G03X1452213Y696523I-16078J-949D01*
G01X1442213D01*
G03X1432300Y667723I0J-16106D01*
G01Y662213D01*
G03X1424149Y652050I7413J-14296D01*
G03X1422541Y651561I3875J-15630D01*
G02X1422015Y651848I-136J376D01*
G03X1417925Y659411I-15696J-3601D01*
G01Y670197D01*
G03X1416827Y676042I-16106J0D01*
G03X1422425Y688248I-10508J12206D01*
G01Y698248D01*
G03X1421722Y702954I-16106J0D01*
G02X1422216Y703455I383J117D01*
G03X1426267Y702820I4499J15462D01*
G03X1453363Y708663I11820J10936D01*
G01X1455300Y710600D01*
X1458712D01*
X1499817Y646093D01*
G02X1499693Y645540I-337J-215D01*
G03X1492219Y631998I8531J-13542D01*
G01Y631420D01*
G37*
G36*
G01X1476697Y915616D02*
X1478697Y914292D01*
X1481235Y912676D01*
X1556656Y897653D01*
G02X1556915Y897046I-78J-392D01*
G03X1554860Y884565I13585J-8646D01*
G02X1554429Y884072I-388J-95D01*
G03X1507298Y841710I-4528J-42362D01*
G01Y824854D01*
G02X1506686Y824514I-400J-1D01*
G01X1477680Y842644D01*
G02X1477681Y843322I212J339D01*
G03X1457059Y894091I-14688J23606D01*
G02X1456575Y894458I-85J391D01*
G03X1456368Y896242I-16075J-961D01*
G03X1432132Y907258I-8368J13758D01*
G03X1424434Y894584I8368J-13758D01*
G03X1419456Y879823I10866J-11884D01*
G02X1418850Y879413I-394J-71D01*
G01X1408439Y885920D01*
X1408444Y886036D01*
G03X1397769Y901862I-16089J661D01*
G01X1397706Y901884D01*
X1388472Y915837D01*
G02X1388599Y916401I333J221D01*
G03X1388701Y916462I-8214J13850D01*
G03X1384827Y947273I2299J15938D01*
G01X1380900Y951200D01*
Y952599D01*
X1380932Y952648D01*
G03X1382800Y956698I-13551J8706D01*
G03X1394017Y969660I-4700J15402D01*
G02X1394633Y969933I395J-60D01*
G01X1476697Y915616D01*
G37*
G36*
G01X1475011Y395752D02*
X1475110Y395918D01*
G03X1451495Y416974I-13810J8282D01*
G03X1438240Y419655I-9525J-12984D01*
G01X1438157Y419635D01*
X1434424Y422054D01*
X1434421Y422159D01*
G03X1434395Y422735I-16197J-443D01*
G02X1434794Y423160I399J25D01*
G01X1523323D01*
G02X1523570Y422446I0J-400D01*
G03X1507298Y388954I26332J-33492D01*
G01Y375566D01*
G02X1506681Y375230I-400J0D01*
G01X1475011Y395752D01*
G37*
G36*
G01X1461189Y781476D02*
X1429700Y830864D01*
Y832500D01*
X1430800Y833600D01*
X1432422D01*
X1481813Y802730D01*
G02X1481721Y802010I-212J-339D01*
G03X1470466Y785068I4879J-15451D01*
G02X1470105Y784633I-399J-37D01*
G03X1461769Y781373I1504J-16133D01*
G02X1461189Y781476I-243J318D01*
G37*
G36*
G01X1494993Y759465D02*
G03X1492662Y771022I-15960J2794D01*
G02X1492844Y771608I336J217D01*
G03X1502627Y788944I-6244J14952D01*
G02X1503234Y789342I396J59D01*
G01X1524008Y776358D01*
G02X1524129Y775797I-212J-339D01*
G03X1521884Y770674I13402J-8927D01*
G03X1512881Y751249I8234J-15615D01*
G02X1512203Y750885I-391J-86D01*
G03X1512088Y751003I-11661J-11250D01*
G03X1495450Y759002I-14089J-8002D01*
G02X1494993Y759465I-63J395D01*
G37*
G36*
G01X1604994Y244661D02*
Y240560D01*
G03X1605304Y237416I16106J1D01*
G02X1604679Y237012I-392J-79D01*
G01X1576630Y257073D01*
X1576710Y257227D01*
G03X1570846Y278387I-14285J7434D01*
G01X1570751Y278445D01*
Y280390D01*
X1578991D01*
X1606853Y262298D01*
X1606868Y262212D01*
G03X1609474Y255807I15871J2725D01*
G03X1604994Y244661I11625J-11146D01*
G37*
G36*
G01X1616846Y1166338D02*
G03X1615217Y1166350I-933J-16076D01*
G03X1578820Y1172752I-23092J-24618D01*
G02X1578269Y1173048I-157J368D01*
G03X1567500Y1185456I-15845J-2874D01*
G01Y1190260D01*
G03X1571693Y1192768I-6074J14914D01*
G01X1571766Y1192829D01*
X1601909Y1186697D01*
X1619873Y1174806D01*
X1619762Y1174639D01*
G03X1617057Y1166527I13375J-8967D01*
G02X1616846Y1166338I-200J11D01*
G37*
G36*
G01X1636521Y724000D02*
G03X1619269Y735232I-15383J-4762D01*
G01X1619174Y735221D01*
X1572532Y781435D01*
G02X1572600Y782058I281J285D01*
G03X1592504Y818110I-22698J36052D01*
G01Y841710D01*
G03X1578137Y873612I-42603J0D01*
G02X1578210Y874263I265J300D01*
G03X1584060Y879714I-7709J14138D01*
G03X1599390Y888987I739J16086D01*
G01X1599457Y889129D01*
X1624556Y884129D01*
X1624595Y884026D01*
G03X1632669Y875241I15049J5729D01*
G03X1636629Y871169I13343J9015D01*
G02X1636666Y870549I-233J-325D01*
G03X1651130Y779731I37251J-40628D01*
G02X1651226Y779064I-165J-364D01*
G03X1646097Y770674I10519J-12193D01*
G03X1643908Y740812I8234J-15615D01*
G02X1643940Y740192I-236J-323D01*
G03X1638638Y728248I10802J-11944D01*
G01Y724000D01*
X1636521D01*
G37*
G36*
G01X1677763Y768523D02*
X1677743Y768700D01*
G03X1676044Y774272I-15998J-1833D01*
G02X1676382Y774856I355J184D01*
G03X1724448Y807900I-2464J55065D01*
G01X1743360D01*
X1762139Y782566D01*
X1772021Y774942D01*
X1771936Y774791D01*
G03X1770309Y770674I14020J-7921D01*
G03X1768120Y740812I8234J-15615D01*
G02X1768152Y740192I-236J-323D01*
G03X1765142Y736528I10804J-11944D01*
G03X1750615Y720500I1579J-16028D01*
G01Y716500D01*
G03X1763056Y700817I16105J0D01*
G03X1762850Y698251I15900J-2568D01*
G01Y688248D01*
G03X1763948Y682403I16106J0D01*
G03X1758350Y670197I10508J-12206D01*
G01Y651299D01*
G03X1763950Y639091I16107J0D01*
G03X1764706Y625748I15006J-5843D01*
G03X1763444Y613924I14250J-7500D01*
G03X1767179Y593991I15099J-7487D01*
G02X1766909Y593296I-270J-295D01*
G01X1729389D01*
X1716177Y606509D01*
G02X1716182Y607080I282J283D01*
G03X1718354Y609668I-11180J11589D01*
G02X1719001Y609689I331J-224D01*
G03X1747656Y619498I12649J9809D01*
G01Y631998D01*
G03X1741434Y644665I-16005J0D01*
G01X1741356Y644725D01*
Y646998D01*
G03X1723686Y662917I-16006J0D01*
G02X1723244Y663315I-42J398D01*
G01Y668417D01*
G03X1713805Y683078I-16106J0D01*
G03X1699638Y691523I-14167J-7661D01*
G01X1689638D01*
G03X1674490Y680888I0J-16106D01*
G01X1674487Y680878D01*
X1674394Y680689D01*
X1674034Y680865D01*
X1670400Y684466D01*
X1670426Y684575D01*
G03X1670850Y688245I-15682J3671D01*
G01Y698248D01*
G03X1670147Y702954I-16106J0D01*
G02X1670641Y703455I383J117D01*
G03X1678945Y703270I4499J15462D01*
G03X1692000Y732601I7693J14147D01*
G01Y737621D01*
G03X1685638Y768523I-6362J14796D01*
G01X1677763D01*
G37*
G36*
G01X1705472Y914629D02*
G03X1691000Y939665I-13372J8971D01*
G02X1690707Y940363I-27J399D01*
G03X1694814Y946060I-10695J12039D01*
G01X1723554D01*
X1726814Y942800D01*
X1742095D01*
G02X1742336Y942080I1J-400D01*
G03X1761615Y942117I9664J-12880D01*
G02X1761826Y942837I239J321D01*
G03X1770973Y946695I-1067J15303D01*
G03X1777666Y945238I6694J14649D01*
G01X1782666D01*
G03X1792539Y948619I0J16106D01*
G03X1799316Y947245I6514J14727D01*
G03X1808396Y945925I6761J14615D01*
G02X1808854Y945529I58J-396D01*
G01Y942714D01*
G03X1805482Y913649I4997J-15308D01*
G03X1805873Y912985I14067J7837D01*
G03X1809122Y897194I15279J-5086D01*
G03X1808132Y887798I14815J-6311D01*
G03X1808302Y883608I16038J-1448D01*
G02X1807815Y883151I-394J-68D01*
G03X1762658Y865600I-9882J-41441D01*
G01X1739993D01*
X1731105Y877590D01*
X1717026Y888516D01*
X1717137Y888673D01*
G03X1705760Y914008I-13127J9327D01*
G02X1705472Y914629I44J398D01*
G37*
G36*
G01X1701094Y973816D02*
X1698085Y976825D01*
Y989908D01*
X1699556Y991379D01*
X1730382D01*
X1732066Y993063D01*
X1732167Y993047D01*
G03X1732418Y993028I246J1582D01*
G01X1734018D01*
G03X1734634Y993151I1J1601D01*
G01X1734671Y993166D01*
X1736349D01*
X1737790Y991725D01*
X1740270D01*
X1740527Y991468D01*
X1744556D01*
Y991368D01*
X1749798D01*
Y979160D01*
X1744454Y973816D01*
X1701094D01*
G37*
G36*
G01X1709181Y993554D02*
X1708181Y994554D01*
Y1001554D01*
X1718181Y1011554D01*
X1730181D01*
X1730681Y1011054D01*
Y1005554D01*
X1732681Y1003553D01*
Y999054D01*
X1734681Y997054D01*
Y994554D01*
X1734495Y994368D01*
X1731671D01*
X1731358Y994054D01*
X1731181D01*
X1730681Y993554D01*
X1709181D01*
G37*
G36*
G01X1770949Y1040345D02*
G03X1760113Y1031186I3914J-15620D01*
G03X1758038Y1030560I3603J-15694D01*
G03X1753514Y1030525I-2139J-15960D01*
G01X1753499Y1030523D01*
X1745049D01*
X1742582Y1028056D01*
X1740325D01*
X1740272Y1028096D01*
G03X1730661Y1031304I-9612J-12795D01*
G01X1722222D01*
X1722207Y1031306D01*
G03X1717155I-2526J-16005D01*
G01X1717140Y1031304D01*
X1708215D01*
G03X1707914Y1031301I9J-16003D01*
G02X1707515Y1031785I-8J400D01*
G03X1701183Y1048229I-15744J3379D01*
G02X1701252Y1048918I234J325D01*
G03X1705981Y1052170I-6614J14682D01*
G01X1763223D01*
G03X1770093Y1044611I15320J7023D01*
G03X1771218Y1040894I15863J2772D01*
G02X1770949Y1040345I-366J-161D01*
G37*
G36*
G01X1705570Y992847D02*
X1691261D01*
X1690261Y993847D01*
Y1005347D01*
X1691261Y1006347D01*
X1705191D01*
X1706626Y1004912D01*
Y993903D01*
X1705570Y992847D01*
G37*
G36*
G01X1760467Y1005458D02*
X1763841Y1002084D01*
Y991902D01*
X1763662Y991723D01*
Y980227D01*
X1763841Y980048D01*
Y979617D01*
X1763285Y979061D01*
X1751704D01*
X1751315Y979450D01*
X1751359Y979555D01*
Y1002175D01*
G03X1752065Y1004597I-1496J1750D01*
G01X1752056Y1004626D01*
Y1006618D01*
X1753757Y1008319D01*
G02X1754098Y1008178I141J-141D01*
G01Y1007998D01*
X1757502D01*
Y1008074D01*
X1757748Y1008177D01*
X1759283Y1006642D01*
X1759297Y1006591D01*
G03X1760416Y1005472I1544J425D01*
G01X1760467Y1005458D01*
G37*
G36*
G01X1752363Y1010159D02*
X1750997Y1011525D01*
X1750963D01*
Y1015222D01*
X1751263Y1015522D01*
X1759863D01*
Y1015525D01*
X1761405D01*
X1761417Y1015338D01*
G03X1762828Y1013366I2297J153D01*
G01Y1010764D01*
X1762223Y1010159D01*
X1757502D01*
Y1010602D01*
X1754098D01*
Y1010159D01*
X1752363D01*
G37*
G36*
G01X1842386Y967433D02*
X1805103D01*
X1803363Y969173D01*
Y990125D01*
X1806863Y993625D01*
X1865700D01*
X1865974Y993351D01*
Y992069D01*
X1866254Y991789D01*
X1871699D01*
X1874863Y988625D01*
Y974631D01*
X1869417Y969185D01*
X1844138D01*
X1842386Y967433D01*
G37*
G36*
G01X1782604Y969225D02*
X1779604Y972225D01*
X1773363D01*
X1765352Y980236D01*
Y991368D01*
X1770644D01*
Y991468D01*
X1773712D01*
X1774144Y991900D01*
X1787513D01*
X1789363Y990050D01*
Y970663D01*
X1787925Y969225D01*
X1782604D01*
G37*
G36*
G01X1792063Y1008425D02*
X1791363Y1009125D01*
Y1012061D01*
G02X1791861Y1012449I400J0D01*
G03X1792256Y1012400I393J1552D01*
G01X1793856D01*
G03X1795458Y1014001I0J1602D01*
G01Y1015601D01*
G03X1795259Y1016374I-1601J0D01*
G01X1795186Y1016505D01*
X1795235Y1016554D01*
Y1020597D01*
X1796363Y1021725D01*
X1799260D01*
X1800260Y1020725D01*
Y1009122D01*
X1799563Y1008425D01*
X1792063D01*
G37*
G36*
G01X1836261Y795447D02*
Y790779D01*
X1840929D01*
X1842109Y789599D01*
X1842620D01*
Y785281D01*
X1851332D01*
X1851358Y785274D01*
G03X1853066Y784897I4320J15513D01*
G01X1853129Y784887D01*
X1855647Y782368D01*
X1885802D01*
G03X1896868Y776899I17544J21569D01*
G02X1897100Y776276I-93J-389D01*
G03X1894522Y770674I13068J-9408D01*
G03X1891292Y768483I8234J-15615D01*
G03X1873517Y744377I-4123J-15566D01*
G02X1873367Y743812I-339J-212D01*
G03X1865227Y733000I7603J-14195D01*
G01X1854168D01*
X1829135Y770856D01*
X1817661Y779710D01*
G02X1817719Y780381I244J317D01*
G03X1834594Y796408I-19785J37730D01*
G02X1835221Y796487I344J-204D01*
G01X1836261Y795447D01*
G37*
G36*
G01X1856323Y804600D02*
X1848323D01*
X1846323Y806600D01*
Y823342D01*
X1850581Y827600D01*
X1855823D01*
X1857323Y826100D01*
Y805600D01*
X1856323Y804600D01*
G37*
G36*
G01X1845102Y824944D02*
X1834147D01*
X1832929Y826162D01*
Y846284D01*
X1834973Y848328D01*
X1845659D01*
X1851492Y842495D01*
Y831334D01*
X1845102Y824944D01*
G37*
G36*
G01X1884029Y797369D02*
X1861861D01*
X1860433Y798797D01*
Y802762D01*
X1858750Y804445D01*
Y838054D01*
X1842037Y854767D01*
Y866363D01*
X1844543Y868869D01*
X1882118D01*
X1885618Y865369D01*
Y798958D01*
X1884029Y797369D01*
G37*
G36*
G01X1851301Y884296D02*
X1849301Y886296D01*
Y902266D01*
G03X1849602Y903200I-1301J935D01*
G01Y904800D01*
G03X1849289Y905750I-1602J-1D01*
G03X1849602Y906700I-1289J951D01*
G01Y908102D01*
X1850296Y908796D01*
X1856124D01*
Y908308D01*
X1868444D01*
Y903014D01*
X1868544D01*
Y899247D01*
X1868976Y898815D01*
Y886146D01*
X1867126Y884296D01*
X1851301D01*
G37*
G36*
G01X1850157Y929979D02*
X1843517D01*
X1842766Y930730D01*
Y952662D01*
X1843362Y953258D01*
X1850457D01*
X1850625Y953090D01*
Y930447D01*
X1850157Y929979D01*
G37*
G36*
G01X1848497Y909823D02*
X1847811Y910509D01*
Y921484D01*
X1848986Y922659D01*
X1856631D01*
Y922300D01*
X1879660D01*
X1880357Y921603D01*
X1883694D01*
X1885029Y920268D01*
Y915687D01*
X1884112Y914770D01*
X1884052Y914758D01*
G03X1882242Y912948I448J-2258D01*
G01X1882230Y912888D01*
X1879160Y909818D01*
X1868978D01*
X1868799Y909998D01*
X1849798D01*
X1849669Y909868D01*
X1849615Y909854D01*
G03X1849197Y909686I382J-1555D01*
G01X1849151Y909659D01*
X1848849D01*
X1848803Y909686D01*
G03X1848539Y909808I-801J-1387D01*
G01X1848497Y909823D01*
G37*
G36*
G01X1853861Y923860D02*
X1852563Y925159D01*
Y952932D01*
X1853000Y953369D01*
X1858381D01*
X1859647Y954635D01*
Y960824D01*
X1860545Y961722D01*
X1865222D01*
X1865895Y961049D01*
Y934535D01*
X1868496Y931934D01*
Y929104D01*
X1868444D01*
Y923860D01*
X1853861D01*
G37*
G36*
G01X1839231Y940240D02*
X1825619D01*
X1823855Y942004D01*
Y952517D01*
X1825863Y954525D01*
X1840317D01*
X1841432Y953410D01*
Y942441D01*
X1839231Y940240D01*
G37*
G36*
G01X1857603Y954948D02*
X1844123D01*
X1843733Y955338D01*
Y965996D01*
X1844385Y966648D01*
X1857393D01*
X1857915Y966126D01*
Y955260D01*
X1857603Y954948D01*
G37*
G36*
G01X1844863Y995125D02*
X1843863Y996125D01*
Y1003125D01*
X1845363Y1004625D01*
X1865863D01*
X1866863Y1003625D01*
Y998447D01*
G03X1865792Y995658I1100J-2022D01*
G02X1865415Y995125I-377J-133D01*
G01X1844863D01*
G37*
G36*
G01X1838463Y1006125D02*
X1827363D01*
X1823915Y1009573D01*
Y1019563D01*
X1825877Y1021525D01*
X1840720D01*
X1842526Y1019719D01*
Y1010188D01*
X1838463Y1006125D01*
G37*
G36*
G01X1913245Y829969D02*
X1901358D01*
X1899218Y832109D01*
Y846011D01*
X1901576Y848369D01*
X1912945D01*
X1914618Y846696D01*
Y831342D01*
X1913245Y829969D01*
G37*
G36*
G01X1886198Y873399D02*
X1885501Y874096D01*
Y881596D01*
X1886201Y882296D01*
X1889137D01*
G02X1889525Y881798I0J-400D01*
G03X1889476Y881403I1552J-393D01*
G01Y879803D01*
G03X1891077Y878202I1601J0D01*
G01X1892677D01*
G03X1893450Y878400I2J1601D01*
G01X1893581Y878473D01*
X1893630Y878424D01*
X1897673D01*
X1898801Y877296D01*
Y874399D01*
X1897801Y873399D01*
X1886198D01*
G37*
G36*
G01X1867448Y935089D02*
X1867096Y935440D01*
Y935573D01*
X1867097Y935581D01*
G03X1867102Y935700I-1597J127D01*
G01Y937300D01*
G03X1867097Y937419I-1602J-8D01*
G01X1867096Y937427D01*
Y937964D01*
X1868047Y938914D01*
Y954836D01*
X1869503Y956292D01*
X1887390D01*
X1888106Y955576D01*
Y943189D01*
X1887136Y942219D01*
X1879223D01*
X1877800Y940796D01*
X1874870D01*
X1872999Y938925D01*
X1872883Y938961D01*
G03X1869995Y936073I-693J-2195D01*
G01X1870031Y935957D01*
X1869163Y935089D01*
X1867448D01*
G37*
G36*
G01X1893032Y912427D02*
X1888460D01*
X1887718Y913169D01*
Y921779D01*
X1888635Y922696D01*
X1892298D01*
X1894077Y920917D01*
Y913472D01*
X1893032Y912427D01*
G37*
%LPC*%
G75*
G36*
G01X700073Y370839D02*
G02X705202Y357372I-10901J-11862D01*
G02X673202Y356857I-15970J-2120D01*
G02X679897Y372150I15970J2121D01*
G03Y372804I-230J327D01*
G02X691142Y401965I9275J13172D01*
G02X700168Y371493I1970J-15989D01*
G03X700073Y370839I176J-359D01*
G37*
G36*
G01X458601Y371354D02*
G02X459353Y369902I-13911J-8125D01*
G02X441659Y347150I-3163J-15797D01*
G02X426833Y371355I-912J16084D01*
G02X442717Y395463I13914J8119D01*
G02X458601Y371354I1970J-15989D01*
G37*
G36*
G01X144963Y28298D02*
G02X142061Y8000I-17700J-7826D01*
G01X85125D01*
G02X69898Y35473I18517J28220D01*
G02X91352Y67656I10121J16495D01*
G02X137387Y36966I12290J-31436D01*
G02X144963Y28298I-10124J-16494D01*
G37*
G36*
G01X452065Y910505D02*
G02X447905Y905300I-14464J7296D01*
G02X424776Y927699I-12823J9900D01*
G02X426420Y929524I12824J-9899D01*
G02X428693Y949605I13718J8616D01*
G03Y949889I-141J142D01*
G02X435810Y976966I11445J11466D01*
G02X440578Y981511I13328J-9209D01*
G03X440420Y982247I-211J340D01*
G02X426502Y1000117I2180J16053D01*
G02X423964Y1001432I6154J14985D01*
G03X423386Y1001261I-214J-338D01*
G02X414119Y1023295I-14714J6777D01*
G03X414374Y1023415I67J188D01*
G02X442049Y1028301I15239J-5495D01*
G02X442963Y1027600I-9395J-13197D01*
G01X452006D01*
G02X458680Y1003370I13194J-9400D01*
G03X458135Y1002890I-161J-366D01*
G02X451159Y984546I-15536J-4590D01*
G03X451317Y983810I212J-340D01*
G02X460499Y956208I-2179J-16053D01*
G02X456583Y949889I-15361J5147D01*
G03Y949605I141J-142D01*
G02X460234Y932263I-11445J-11465D01*
G02X452065Y910505I-14652J-6912D01*
G37*
G36*
G01X657087Y1351633D02*
X657061Y1351802D01*
X657055D01*
G02X663092Y1366803I15945J2298D01*
G01X682908D01*
G02X688945Y1351802I-9908J-12703D01*
G01X688939D01*
X688913Y1351633D01*
G02X657087I-15913J2467D01*
G37*
G36*
G01X148788Y1351745D02*
X148805Y1351784D01*
Y1351802D01*
G02X178015Y1352188I14695J-6602D01*
G01X178212Y1351745D01*
G02X148788I-14712J-6545D01*
G37*
G36*
G01X296860Y1319015D02*
G02X283700Y1312194I-13160J9285D01*
G01X279900D01*
G02X271814Y1342229I0J16106D01*
G02X270131Y1351736I14286J7431D01*
G01X270133Y1351749D01*
Y1351802D01*
G02X301347Y1354861I15967J-2143D01*
G02X306255Y1352041I-5447J-15161D01*
G01X306600Y1351734D01*
G02X311923Y1338092I-10700J-12034D01*
G02X296860Y1319015I-15823J-2992D01*
G37*
G36*
G01X541841Y1334097D02*
G02X536366Y1327378I-14841J6503D01*
G02X506060Y1331022I-15766J-3278D01*
G02X497965Y1351622I6840J14578D01*
G01Y1366803D01*
X564500D01*
Y1357877D01*
G02X565952Y1335700I-10913J-11851D01*
G01X565906Y1335644D01*
Y1335500D01*
G02X542482Y1334228I-12318J10526D01*
G03X541841Y1334097I-274J-291D01*
G37*
G36*
G01X738857Y1263379D02*
G02X734352Y1259117I-13180J9419D01*
G02X708746Y1278632I-13906J8310D01*
G02X714363Y1284392I14043J-8076D01*
G02X714894Y1284888I11321J-11588D01*
G02X720967Y1290120I13281J-9276D01*
G02X738857Y1263379I10533J-12308D01*
G37*
G36*
G01X332370Y949605D02*
G02X336358Y943065I-11445J-11465D01*
G02X321452Y918494I-1058J-16165D01*
G02X306870Y947248I-5854J15106D01*
G03X306878Y947917I-215J337D01*
G02X318425Y977361I9047J13438D01*
G02X321837Y977529I2498J-16006D01*
G02X330553Y986918I15263J-5429D01*
G03X330737Y987485I-162J366D01*
G02X351284Y980819I14000J8152D01*
G03X351100Y980252I162J-366D01*
G02X336189Y955926I-14000J-8152D01*
G02X332370Y949889I-15263J5429D01*
G03Y949605I141J-142D01*
G37*
G36*
G01X26874Y910093D02*
G02X31495Y854874I4621J-27416D01*
G01X31494D01*
Y854875D01*
X8000D01*
Y910090D01*
X26858D01*
X26874Y910093D01*
G37*
G36*
G01X770642Y1014835D02*
G02X800158Y1025165I13358J9165D01*
G02X770642Y1014835I-13358J-9165D01*
G37*
G36*
G01X793742Y645719D02*
G03X794003Y646255I-109J385D01*
G02X793135Y649118I14917J6086D01*
G02X792980Y672737I10880J11881D01*
G02X820050I13535J-8737D01*
G02X824913Y658397I-11035J-11737D01*
G02X824898Y654400I-15993J-1939D01*
G02X813318Y636842I-15978J-2060D01*
G03X813057Y636306I109J-385D01*
G02X813564Y634873I-14917J-6084D01*
G02X814402Y610663I-10197J-12472D01*
G02X787332I-13535J8737D01*
G02X782318Y623799I11035J11737D01*
G02X782179Y628034I15892J2641D01*
G02X793742Y645719I15961J2187D01*
G37*
G36*
G01X1243238Y23038D02*
G02X1240566Y35475I31073J13181D01*
G02X1262022Y67656I10123J16494D01*
G02X1308056Y36967I12289J-31436D01*
G02X1317097Y23173I-10123J-16495D01*
G01X1317121Y23001D01*
Y8000D01*
X1243254D01*
Y23001D01*
X1243238Y23038D01*
G37*
G36*
G01X1059674Y99655D02*
G03X1060138Y99313I397J52D01*
G02X1047564Y78360I2716J-15879D01*
G03X1047034Y78605I-380J-126D01*
G02X1038504Y77628I-6032J14938D01*
G02X1021239Y87096I-2501J15915D01*
G02X1017588Y100045I12264J10447D01*
G02Y105042I15915J2498D01*
G02Y110042I15915J2500D01*
G02X1017416Y113406I15915J2500D01*
G02X1014805Y124031I13409J8929D01*
G02X1014766Y128217I15953J2242D01*
G02X1014778Y131923I16009J1801D01*
G02X1014850Y136281I15996J1915D01*
G02X1046814Y135340I16040J1499D01*
G02X1046771Y131933I-16040J-1501D01*
G02X1046799Y128353I-15996J-1915D01*
G02X1059618Y110044I-3096J-15810D01*
G02Y105043I-15915J-2501D01*
G02Y100044I-15915J-2500D01*
G02X1059674Y99655I-15917J-2490D01*
G37*
G36*
G01X997189Y58800D02*
G02X1024111I13461J8850D01*
G02X997189I-13461J-8850D01*
G37*
G36*
G01X1123366Y1586608D02*
G03X1122697I-334J-220D01*
G02Y1590558I-3012J1975D01*
G03X1123366I335J220D01*
G02Y1586608I3012J-1975D01*
G37*
G36*
G01X1105138D02*
G03X1104469I-334J-220D01*
G02Y1590558I-3012J1975D01*
G03X1105138I334J220D01*
G02Y1586608I3012J-1975D01*
G37*
G36*
G01X1095005Y1553378D02*
G03X1094469I-268J-297D01*
G02X1091290Y1556706I-1543J1708D01*
G03Y1557268I-284J281D01*
G02X1094469Y1560596I1636J1620D01*
G03X1095005I268J297D01*
G02X1098184Y1557268I1543J-1708D01*
G03Y1556706I284J-281D01*
G02X1095005Y1553378I-1636J-1620D01*
G37*
G36*
G01X1097575Y1533801D02*
G03Y1533239I284J-281D01*
G02X1094301I-1637J-1619D01*
G03Y1533801I-284J281D01*
G02X1097575I1637J1619D01*
G37*
G36*
G01X1092455D02*
G03Y1533239I284J-281D01*
G02X1089181I-1637J-1619D01*
G03Y1533801I-284J281D01*
G02X1092455I1637J1619D01*
G37*
G36*
G01X1608616Y1351750D02*
X1608619Y1351767D01*
Y1351802D01*
G02X1640381I15881J-2702D01*
G01Y1351767D01*
X1640384Y1351750D01*
G02X1608616I-15884J-2650D01*
G37*
G36*
G01X1724645Y1351751D02*
X1724654Y1351780D01*
Y1351802D01*
G02X1755346I15346J-4902D01*
G01Y1351780D01*
X1755355Y1351751D01*
G02X1724645I-15355J-4851D01*
G37*
G36*
G01X1857725Y1348608D02*
G02X1826275I-15725J-3908D01*
G01X1826370D01*
X1826409Y1348758D01*
G02X1857591I15591J-4058D01*
G01X1857630Y1348608D01*
X1857725D01*
G37*
G36*
G01X1911819Y1327785D02*
G02X1890218Y1340604I-3320J19015D01*
G02X1926843Y1352812I18282J6196D01*
G01Y1340788D01*
G02X1911842Y1327788I-18343J6012D01*
G01X1911836D01*
X1911819Y1327785D01*
G37*
G36*
G01X1514648Y1351737D02*
G02X1508650Y1327822I-13048J-9437D01*
G02X1479259Y1341030I-13989J8177D01*
G02X1475562Y1351598I12403J10270D01*
G01Y1351802D01*
X1475560D01*
G02X1487282Y1366803I16102J-502D01*
G01X1496042D01*
G02X1506464Y1357658I-4380J-15503D01*
G02X1514610Y1351802I-4863J-15359D01*
G01Y1351790D01*
X1514648Y1351737D01*
G37*
G36*
G01X1926843Y8000D02*
X1903030D01*
G02X1886340I-8345J13654D01*
G01X1794436D01*
Y22999D01*
X1794420Y23036D01*
G02X1791747Y35475I31072J13184D01*
G02X1808130Y70282I10123J16494D01*
G03X1808634Y70801I130J378D01*
G02X1842183Y66073I18066J6799D01*
G03X1842305Y65487I321J-239D01*
G02X1859237Y36967I-16813J-29268D01*
G02X1865577Y30645I-10125J-16493D01*
G03X1866299Y30733I341J210D01*
G02X1911842Y46023I28386J-9079D01*
G01X1926843D01*
Y8000D01*
G37*
G36*
G01X1703732Y532816D02*
G02X1717226Y533354I7330J-14346D01*
G02X1740275Y524708I7874J-14054D01*
G02X1737519Y492685I-256J-16108D01*
G02X1721207Y500307I-2500J15915D01*
G02X1713848Y502348I503J16102D01*
G02X1703732Y532816I-6354J14804D01*
G37*
G54D90*
X1852000Y905750D03*
G54D88*
X114300Y992362D03*
X181000Y580362D03*
X1756100Y1004362D03*
G54D84*
X63128Y89671D03*
X1861177Y91072D03*
G54D89*
X954921Y24410D03*
X929331D03*
X947047Y28347D03*
X937205D03*
Y12599D03*
X929331Y710629D03*
X1097441Y403543D03*
X1105315Y391732D03*
X1123031Y403543D03*
X1097441Y32284D03*
Y24410D03*
X1105315Y28347D03*
Y12599D03*
X1123031Y32284D03*
Y24410D03*
X1115157Y28347D03*
G54D86*
X522867Y1231097D03*
X571400Y1000100D03*
G54D85*
X291601Y418503D03*
X452800Y420912D03*
X705348Y478425D03*
X1020250Y357188D03*
X1138198Y832424D03*
X1873500Y1329000D03*
X1226045Y431102D03*
X1355733Y1241900D03*
G54D87*
X91900Y975800D03*
X89093Y979495D03*
Y982895D03*
X66250Y965650D03*
X91900Y969800D03*
X94300D03*
X128063Y553225D03*
X127450Y551150D03*
Y545650D03*
X118641Y1000216D03*
X139550Y545650D03*
Y551150D03*
X158600Y557800D03*
X161000D03*
X158600Y563800D03*
X155793Y567495D03*
Y570895D03*
X150436Y998474D03*
X152636D03*
X155241Y1000144D03*
X156056Y1001601D03*
Y1004001D03*
X185341Y588216D03*
X217136Y586474D03*
X219336D03*
X221941Y588144D03*
X222756Y589601D03*
Y592001D03*
X706132Y944702D03*
X708532D03*
X702683Y916689D03*
X705083D03*
X749768Y895098D03*
X752168D03*
X706132Y938702D03*
X708532D03*
X737182Y903002D03*
X742782D03*
X744483Y904189D03*
X742782Y905202D03*
X758417Y875189D03*
X752168Y901098D03*
X1700433Y986463D03*
X1705933D03*
X1732018Y990629D03*
X1734418D03*
X1732018Y996629D03*
X1729211Y1000324D03*
Y1003724D03*
X1704461Y1002347D03*
X1701061D03*
X1700433Y998563D03*
Y994063D03*
X1760441Y1012216D03*
X1792236Y1010474D03*
X1794436D03*
X1797041Y1012144D03*
X1797856Y1013601D03*
Y1016001D03*
X1852000Y902800D03*
X1863500Y935300D03*
Y937700D03*
X1860550Y955750D03*
X1865050D03*
X1854500Y963300D03*
X1852950Y961250D03*
Y955750D03*
X1890677Y875803D03*
X1893077D03*
X1889220Y876618D03*
X1887550Y879223D03*
Y881423D03*
X1874571Y944266D03*
X1877971D03*
%LPD*%
G75*
G54D10*
X15157Y21653D03*
Y474409D03*
X904921Y-25591D03*
Y564960D03*
X975787Y-25590D03*
X975786Y564960D03*
X1104527Y1630792D03*
X1894685Y21654D03*
X1894684Y474409D03*
G54D20*
X131201Y377154D03*
X131200Y829910D03*
X131201Y1282666D03*
X379232Y377154D03*
Y829910D03*
Y1282666D03*
X627263Y377154D03*
Y829910D03*
Y1282666D03*
X796457Y263003D03*
Y735444D03*
X961418Y1087413D03*
Y1429932D03*
X1181890Y555917D03*
X1181870Y969280D03*
X1181890Y1559854D03*
X1301870Y377154D03*
Y829910D03*
Y1282666D03*
X1549901Y377154D03*
Y829910D03*
Y1282666D03*
X1797933Y377154D03*
Y829910D03*
Y1282666D03*
G54D11*
X24508Y5500D03*
X5500Y61492D03*
Y56492D03*
Y51492D03*
Y46492D03*
Y41492D03*
Y66492D03*
Y81492D03*
Y76492D03*
Y96492D03*
Y91492D03*
Y86492D03*
Y71492D03*
Y101492D03*
Y111492D03*
Y116492D03*
Y106492D03*
Y126492D03*
Y121492D03*
Y141492D03*
Y151492D03*
Y161492D03*
Y156492D03*
Y146492D03*
Y131492D03*
Y136492D03*
Y181492D03*
Y191492D03*
Y201492D03*
Y211492D03*
Y171492D03*
Y206492D03*
Y196492D03*
Y176492D03*
Y166492D03*
Y186492D03*
Y231492D03*
Y241492D03*
Y251492D03*
Y261492D03*
Y221492D03*
Y256492D03*
Y246492D03*
Y226492D03*
Y216492D03*
Y236492D03*
Y281492D03*
Y291492D03*
Y301492D03*
Y271492D03*
Y306492D03*
Y296492D03*
Y286492D03*
Y276492D03*
Y266492D03*
Y331492D03*
Y341492D03*
Y351492D03*
Y311492D03*
Y321492D03*
Y356492D03*
Y346492D03*
Y336492D03*
Y326492D03*
Y316492D03*
Y381492D03*
Y391492D03*
Y401492D03*
Y361492D03*
Y371492D03*
Y406492D03*
Y396492D03*
Y386492D03*
Y376492D03*
Y366492D03*
Y451492D03*
Y441492D03*
Y431492D03*
Y421492D03*
Y411492D03*
Y416492D03*
Y436492D03*
Y446492D03*
Y426492D03*
Y501492D03*
Y456492D03*
Y496492D03*
Y531492D03*
Y551492D03*
Y541492D03*
Y521492D03*
Y511492D03*
Y536492D03*
Y546492D03*
Y506492D03*
Y516492D03*
Y526492D03*
Y581492D03*
Y591492D03*
Y571492D03*
Y561492D03*
Y586492D03*
Y596492D03*
Y556492D03*
Y566492D03*
Y576492D03*
Y631492D03*
Y641492D03*
Y621492D03*
Y611492D03*
Y601492D03*
Y636492D03*
Y646492D03*
Y606492D03*
Y616492D03*
Y626492D03*
Y681492D03*
Y691492D03*
Y671492D03*
Y661492D03*
Y651492D03*
Y686492D03*
Y696492D03*
Y656492D03*
Y666492D03*
Y676492D03*
Y731492D03*
Y741492D03*
Y721492D03*
Y711492D03*
Y701492D03*
Y736492D03*
Y706492D03*
Y716492D03*
Y726492D03*
Y781492D03*
Y791492D03*
Y771492D03*
Y761492D03*
Y751492D03*
Y786492D03*
Y746492D03*
Y756492D03*
Y766492D03*
Y776492D03*
Y831492D03*
Y841492D03*
Y821492D03*
Y811492D03*
Y801492D03*
Y836492D03*
Y796492D03*
Y806492D03*
Y816492D03*
Y826492D03*
Y881492D03*
Y871492D03*
Y861492D03*
Y851492D03*
Y886492D03*
Y846492D03*
Y856492D03*
Y866492D03*
Y876492D03*
Y931492D03*
Y921492D03*
Y911492D03*
Y901492D03*
Y891492D03*
Y936492D03*
Y896492D03*
Y906492D03*
Y916492D03*
Y926492D03*
Y976492D03*
Y981492D03*
Y986492D03*
Y966492D03*
Y956492D03*
Y961492D03*
Y971492D03*
Y951492D03*
Y941492D03*
Y946492D03*
Y991492D03*
Y996492D03*
Y1001492D03*
Y1006492D03*
Y1026492D03*
Y1016492D03*
Y1011492D03*
Y1021492D03*
Y1031492D03*
Y1036492D03*
Y1066492D03*
Y1056492D03*
Y1046492D03*
Y1041492D03*
Y1051492D03*
Y1061492D03*
Y1071492D03*
Y1081492D03*
Y1076492D03*
Y1121492D03*
Y1131492D03*
Y1111492D03*
Y1101492D03*
Y1091492D03*
Y1086492D03*
Y1096492D03*
Y1106492D03*
Y1116492D03*
Y1126492D03*
Y1171492D03*
Y1161492D03*
Y1151492D03*
Y1141492D03*
Y1136492D03*
Y1146492D03*
Y1156492D03*
Y1166492D03*
Y1176492D03*
Y1221492D03*
Y1211492D03*
Y1201492D03*
Y1191492D03*
Y1181492D03*
Y1186492D03*
Y1196492D03*
Y1206492D03*
Y1216492D03*
Y1226492D03*
Y1271492D03*
Y1261492D03*
Y1251492D03*
Y1241492D03*
Y1231492D03*
Y1236492D03*
Y1246492D03*
Y1256492D03*
Y1266492D03*
Y1276492D03*
Y1321492D03*
Y1311492D03*
Y1301492D03*
Y1291492D03*
Y1281492D03*
Y1286492D03*
Y1296492D03*
Y1306492D03*
Y1316492D03*
X8983Y1368303D03*
X13983D03*
X18983D03*
X23983D03*
X5500Y1361492D03*
Y1351492D03*
Y1341492D03*
Y1331492D03*
Y1336492D03*
Y1346492D03*
Y1356492D03*
Y1326492D03*
X29508Y5500D03*
X39508D03*
X34508D03*
X44508D03*
X64508D03*
X69508D03*
X54508D03*
X49508D03*
X59508D03*
X28983Y1368303D03*
X33983D03*
X38983D03*
X43983D03*
X48983D03*
X53983D03*
X58983D03*
X63983D03*
X68983D03*
X114508Y5500D03*
X119508D03*
X104508D03*
X94508D03*
X84508D03*
X74508D03*
X79508D03*
X89508D03*
X99508D03*
X109508D03*
X119763Y550725D03*
Y546225D03*
Y555225D03*
X83100Y984800D03*
X78600D03*
X83100Y980300D03*
X78600D03*
Y989300D03*
X83100D03*
X73983Y1368303D03*
X78983D03*
X83983D03*
X88983D03*
X93983D03*
X98983D03*
X107374Y1369303D03*
X112374D03*
X117374D03*
X134508Y5500D03*
X124508D03*
X129508D03*
X169508D03*
X159508D03*
X149508D03*
X139508D03*
X154508D03*
X164508D03*
X144508D03*
X124263Y546225D03*
Y550725D03*
Y555225D03*
X141978Y958572D03*
X142006Y978425D03*
X122374Y1369303D03*
X127374D03*
X132374D03*
X137374D03*
X142374D03*
X147374D03*
X152374D03*
X157374D03*
X162374D03*
X167374D03*
X209508Y5500D03*
X199508D03*
X189508D03*
X179508D03*
X204508D03*
X214508D03*
X174508D03*
X184508D03*
X194508D03*
X209863Y566625D03*
X199102Y969717D03*
Y974717D03*
X183584Y974789D03*
Y969789D03*
X199392Y985113D03*
X183551Y984789D03*
X212063Y976725D03*
X203063D03*
X207563D03*
X216563D03*
X212063Y981725D03*
X216563D03*
X207563D03*
X203063D03*
X199392Y990113D03*
X183551Y989789D03*
X172374Y1369303D03*
X177374D03*
X182374D03*
X187374D03*
X192374D03*
X197374D03*
X202374D03*
X207374D03*
X212374D03*
X217374D03*
X259508Y5500D03*
X249508D03*
X239508D03*
X229508D03*
X219508D03*
X224508D03*
X234508D03*
X244508D03*
X254508D03*
X264508D03*
X250650Y556997D03*
Y561997D03*
X265545Y556794D03*
Y561794D03*
X250661Y572936D03*
Y577936D03*
X265590Y572801D03*
Y577801D03*
X225563Y976725D03*
X221063D03*
X225563Y981725D03*
X221063D03*
X222374Y1369303D03*
X227374D03*
X232374D03*
X237374D03*
X242374D03*
X247374D03*
X252374D03*
X257374D03*
X262374D03*
X309508Y5500D03*
X299508D03*
X289508D03*
X279508D03*
X269508D03*
X304508D03*
X314508D03*
X274508D03*
X284508D03*
X294508D03*
X269763Y569725D03*
X287763D03*
X292263D03*
X274263D03*
X283263D03*
X278763D03*
X283263Y564725D03*
X287763D03*
X292263D03*
X274263D03*
X269763D03*
X278763D03*
X267374Y1369303D03*
X272374D03*
X277374D03*
X282374D03*
X287374D03*
X292374D03*
X297374D03*
X302374D03*
X307374D03*
X312374D03*
X359508Y5500D03*
X349508D03*
X339508D03*
X329508D03*
X319508D03*
X324508D03*
X334508D03*
X344508D03*
X354508D03*
X333983Y1368303D03*
X338983D03*
X343983D03*
X348983D03*
X353983D03*
X358983D03*
X363983D03*
X317374Y1369303D03*
X322374D03*
X327374D03*
X395075Y18639D03*
Y13639D03*
X389508Y5500D03*
X379508D03*
X369508D03*
X364508D03*
X374508D03*
X384508D03*
X394508D03*
X395075Y43639D03*
Y38639D03*
Y33639D03*
Y28639D03*
Y23639D03*
X399000Y62000D03*
X396000Y55500D03*
X396075Y50248D03*
X368983Y1368303D03*
X373983D03*
X378983D03*
X383983D03*
X388983D03*
X393983D03*
X398983D03*
X403983D03*
X408983D03*
X413983D03*
X418983D03*
X423983D03*
X428983D03*
X433983D03*
X438983D03*
X443983D03*
X448983D03*
X453983D03*
X458983D03*
X463983D03*
X468983D03*
X473983D03*
X478983D03*
X483983D03*
X488983D03*
X493983D03*
X498983D03*
X503983D03*
X508983D03*
X517374Y1369303D03*
X522374D03*
X527374D03*
X532374D03*
X537374D03*
X542374D03*
X547374D03*
X552374D03*
X557374D03*
X597051Y7699D03*
Y12699D03*
Y17699D03*
X604146Y5500D03*
X597051Y22699D03*
Y27699D03*
Y32699D03*
Y37699D03*
Y42699D03*
X589000Y64000D03*
X594000Y61500D03*
X596000Y56500D03*
X596051Y51090D03*
X567374Y1369303D03*
X572374D03*
X577374D03*
X582374D03*
X587374D03*
X592374D03*
X597374D03*
X602374D03*
X562374D03*
X609146Y5500D03*
X619146D03*
X614146D03*
X629146D03*
X639146D03*
X649146D03*
X654146D03*
X644146D03*
X634146D03*
X624146D03*
X637592Y593186D03*
X641792D03*
Y597386D03*
X637592D03*
X633392Y593186D03*
Y597386D03*
X629192Y593186D03*
Y597386D03*
X641792Y605786D03*
Y601586D03*
X637592D03*
Y605786D03*
X633392D03*
Y601586D03*
X629192D03*
Y605786D03*
X617374Y1369303D03*
X622374D03*
X627374D03*
X632374D03*
X637374D03*
X642374D03*
X647374D03*
X652374D03*
X607374D03*
X612374D03*
X679146Y5500D03*
X689146D03*
X694146D03*
X684146D03*
X659146D03*
X669146D03*
X664146D03*
X674146D03*
X699146D03*
X675913Y586555D03*
Y592955D03*
Y598155D03*
X672082Y582834D03*
X666882D03*
X661682D03*
X656482D03*
X695413Y600755D03*
X699613D03*
X669482Y613934D03*
Y609734D03*
X665282D03*
Y613934D03*
X661082D03*
Y609734D03*
X656882Y613934D03*
Y609734D03*
X675913Y603355D03*
X695413Y604955D03*
X691213Y613355D03*
X695413D03*
X699613D03*
X691213Y609155D03*
X695413D03*
X699613Y604955D03*
Y609155D03*
X702483Y945989D03*
X667374Y1369303D03*
X672374D03*
X677374D03*
X682374D03*
X687374D03*
X692374D03*
X697374D03*
X702374D03*
X657374D03*
X662374D03*
X749146Y5500D03*
X709146D03*
X719146D03*
X729146D03*
X739146D03*
X744146D03*
X734146D03*
X724146D03*
X714146D03*
X704146D03*
X703813Y592355D03*
Y596555D03*
Y600755D03*
X704399Y626799D03*
Y618399D03*
Y622599D03*
X703813Y613355D03*
Y609155D03*
Y604955D03*
X721552Y951317D03*
X725852Y951067D03*
X747374Y1369303D03*
X742374D03*
X717374D03*
X722374D03*
X727374D03*
X732374D03*
X737374D03*
X707374D03*
X712374D03*
X795969Y-1374D03*
X759146Y5500D03*
X769146D03*
X774146D03*
X764146D03*
X754146D03*
X779146D03*
X755500Y1374500D03*
X752500Y1370500D03*
X757287Y1380873D03*
Y1385873D03*
Y1390873D03*
Y1395873D03*
Y1400873D03*
Y1405873D03*
Y1410873D03*
Y1415873D03*
Y1420873D03*
Y1425873D03*
Y1430873D03*
Y1435873D03*
Y1440873D03*
Y1445873D03*
X766156Y1462004D03*
X771156D03*
X790500Y1466500D03*
X786000Y1463500D03*
X756287Y1459264D03*
Y1454264D03*
X779547Y1463004D03*
X792902Y1477964D03*
Y1487964D03*
Y1497964D03*
Y1507964D03*
Y1517964D03*
Y1512964D03*
Y1472964D03*
Y1482964D03*
Y1492964D03*
Y1502964D03*
Y1562964D03*
Y1527964D03*
Y1537964D03*
Y1547964D03*
Y1557964D03*
Y1567964D03*
Y1522964D03*
Y1532964D03*
Y1542964D03*
Y1552964D03*
Y1612964D03*
Y1602964D03*
Y1592964D03*
Y1582964D03*
Y1572964D03*
Y1577964D03*
Y1587964D03*
Y1597964D03*
Y1607964D03*
X797902Y1652964D03*
X792902D03*
Y1642964D03*
Y1632964D03*
Y1622964D03*
Y1627964D03*
Y1637964D03*
Y1647964D03*
Y1617964D03*
X872642Y-140575D03*
Y-135575D03*
Y-130575D03*
Y-125575D03*
X890264Y-147256D03*
X880264D03*
X875264D03*
X885264D03*
X895264D03*
X872642Y-80575D03*
Y-120575D03*
Y-115575D03*
Y-110575D03*
Y-105575D03*
Y-100575D03*
Y-95575D03*
Y-90575D03*
Y-85575D03*
Y-30575D03*
Y-35575D03*
Y-40575D03*
Y-45575D03*
Y-50575D03*
Y-55575D03*
Y-60575D03*
Y-65575D03*
Y-70575D03*
Y-75575D03*
Y-20575D03*
Y-25575D03*
X940264Y-147256D03*
X930264D03*
X925264D03*
X935264D03*
X920264D03*
X910264D03*
X900264D03*
X905264D03*
X915264D03*
X960264D03*
X950264D03*
X955264D03*
X965264D03*
X945264D03*
X990264D03*
X980264D03*
X970264D03*
X975264D03*
X985264D03*
X1010264D03*
X1000264D03*
X1005264D03*
X1015264D03*
X995264D03*
X1040264D03*
X1030264D03*
X1020264D03*
X1025264D03*
X1035264D03*
X1060264D03*
X1050264D03*
X1055264D03*
X1065264D03*
X1045264D03*
X1080264D03*
X1070264D03*
X1075264D03*
X1085264D03*
X1078098Y1652768D03*
X1073098D03*
X1083098D03*
X1088098D03*
X1110264Y-147256D03*
X1100264D03*
X1090264D03*
X1105264D03*
X1095264D03*
X1130264D03*
X1120264D03*
X1115264D03*
X1125264D03*
X1135264D03*
X1093098Y1652768D03*
X1133098D03*
X1123098D03*
X1113098D03*
X1103098D03*
X1108098D03*
X1118098D03*
X1128098D03*
X1098098D03*
X1170264Y-147256D03*
X1155264D03*
X1175602Y-137594D03*
Y-127594D03*
X1160264Y-147256D03*
X1150264D03*
X1140264D03*
X1145264D03*
X1175602Y-132594D03*
Y-142594D03*
X1165264Y-147256D03*
X1175602Y-117594D03*
Y-107594D03*
Y-97594D03*
Y-87594D03*
Y-77594D03*
Y-82594D03*
Y-92594D03*
Y-102594D03*
Y-112594D03*
Y-122594D03*
Y-67594D03*
Y-57594D03*
Y-47594D03*
Y-37594D03*
Y-32594D03*
Y-42594D03*
Y-52594D03*
Y-62594D03*
Y-72594D03*
Y-17594D03*
Y-27594D03*
X1180500Y4000D03*
X1176500Y-500D03*
X1175602Y-22594D03*
Y-12594D03*
Y-7594D03*
X1162000Y1371500D03*
X1169783Y1369303D03*
X1179783D03*
X1174783D03*
X1184783D03*
X1158673Y1417067D03*
Y1407067D03*
Y1397067D03*
Y1387067D03*
Y1377067D03*
Y1412067D03*
Y1402067D03*
Y1392067D03*
Y1382067D03*
Y1422067D03*
Y1442067D03*
Y1452067D03*
X1158500Y1468500D03*
X1158673Y1457067D03*
Y1447067D03*
Y1437067D03*
Y1427067D03*
Y1462067D03*
Y1432067D03*
X1161000Y1474500D03*
X1166673Y1477941D03*
X1171673D03*
X1181673D03*
X1176673D03*
X1143098Y1652768D03*
X1183098D03*
X1173098D03*
X1163098D03*
X1153098D03*
X1158098D03*
X1168098D03*
X1178098D03*
X1138098D03*
X1148098D03*
X1191382Y5500D03*
X1196382D03*
X1186382D03*
X1201382D03*
X1211382D03*
X1221382D03*
X1231382D03*
X1226382D03*
X1216382D03*
X1206382D03*
X1199783Y1369303D03*
X1209783D03*
X1219783D03*
X1229783D03*
X1189783D03*
X1224783D03*
X1214783D03*
X1204783D03*
X1194783D03*
X1191673Y1477941D03*
X1201673D03*
X1214972Y1482642D03*
Y1517642D03*
Y1487642D03*
Y1497642D03*
Y1507642D03*
Y1512642D03*
Y1502642D03*
Y1492642D03*
X1206673Y1477941D03*
X1196673D03*
X1186673D03*
X1211673D03*
X1214972Y1567642D03*
Y1527642D03*
Y1537642D03*
Y1547642D03*
Y1557642D03*
Y1562642D03*
Y1552642D03*
Y1542642D03*
Y1532642D03*
Y1522642D03*
Y1577642D03*
Y1587642D03*
Y1597642D03*
Y1607642D03*
Y1612642D03*
Y1602642D03*
Y1592642D03*
Y1582642D03*
Y1572642D03*
Y1617642D03*
Y1627642D03*
Y1637642D03*
X1213098Y1652768D03*
X1193098D03*
X1203098D03*
X1208098D03*
X1214972Y1642642D03*
Y1632642D03*
X1188098Y1652768D03*
X1198098D03*
X1214972Y1622642D03*
Y1647642D03*
X1251382Y5500D03*
X1261382D03*
X1271382D03*
X1281382D03*
X1276382D03*
X1266382D03*
X1256382D03*
X1241382D03*
X1246382D03*
X1236382D03*
X1249783Y1369303D03*
X1259783D03*
X1269783D03*
X1279783D03*
X1239783D03*
X1274783D03*
X1264783D03*
X1254783D03*
X1234783D03*
X1244783D03*
X1301382Y5500D03*
X1311382D03*
X1296382D03*
X1316382D03*
X1306382D03*
X1291382D03*
X1286382D03*
X1326382D03*
X1321382D03*
X1299783Y1369303D03*
X1309783D03*
X1319783D03*
X1329783D03*
X1289783D03*
X1324783D03*
X1314783D03*
X1304783D03*
X1294783D03*
X1284783D03*
X1363579Y19821D03*
Y14821D03*
Y9821D03*
X1351382Y5500D03*
X1356382D03*
X1346382D03*
X1336382D03*
X1341382D03*
X1331382D03*
X1363579Y44821D03*
Y39821D03*
Y34821D03*
Y29821D03*
Y24821D03*
X1374000Y64500D03*
X1363579Y51618D03*
X1370200Y550500D03*
X1366000D03*
X1378100Y530200D03*
Y534400D03*
X1365500Y538600D03*
X1369700D03*
X1365500Y534400D03*
X1369700D03*
X1373900D03*
X1365500Y530200D03*
X1369700D03*
X1373900D03*
X1375900Y568500D03*
X1366000Y563100D03*
X1370200D03*
Y554700D03*
X1366000D03*
X1370200Y558900D03*
X1366000D03*
X1373700Y582900D03*
X1369500D03*
X1377900Y587100D03*
Y591300D03*
Y595500D03*
X1373700D03*
Y591300D03*
Y587100D03*
X1369500Y595500D03*
Y591300D03*
Y587100D03*
X1377900Y599700D03*
X1373700D03*
X1369500D03*
X1349783Y1369303D03*
X1359783D03*
X1369783D03*
X1339783D03*
X1374783D03*
X1364783D03*
X1354783D03*
X1344783D03*
X1334783D03*
X1396500Y549500D03*
X1386500Y534400D03*
Y530200D03*
X1382300D03*
Y534400D03*
X1396500Y559900D03*
Y554700D03*
Y565100D03*
X1393000Y568500D03*
X1387300D03*
X1381600D03*
X1382100Y587100D03*
X1386300D03*
X1399783Y1369303D03*
X1409783D03*
X1419783D03*
X1379783D03*
X1389783D03*
X1404783D03*
X1414783D03*
X1424783D03*
X1394783D03*
X1384783D03*
X1434441Y590424D03*
X1434581Y586136D03*
X1449783Y1369303D03*
X1459783D03*
X1469783D03*
X1429783D03*
X1439783D03*
X1444783D03*
X1454783D03*
X1464783D03*
X1474783D03*
X1434783D03*
X1499783D03*
X1509783D03*
X1519783D03*
X1479783D03*
X1489783D03*
X1494783D03*
X1484783D03*
X1504783D03*
X1514783D03*
X1565555Y16517D03*
X1568030Y5500D03*
X1565555Y21517D03*
Y26517D03*
Y31517D03*
Y36517D03*
Y41517D03*
X1557000Y64500D03*
X1561500Y62000D03*
X1564000Y57500D03*
X1564555Y52124D03*
X1549783Y1369303D03*
X1559783D03*
X1569783D03*
X1529783D03*
X1539783D03*
X1524783D03*
X1534783D03*
X1544783D03*
X1554783D03*
X1564783D03*
X1603030Y5500D03*
X1613030D03*
X1573030D03*
X1583030D03*
X1593030D03*
X1618030D03*
X1608030D03*
X1598030D03*
X1588030D03*
X1578030D03*
X1614783Y1369303D03*
X1604783D03*
X1599783D03*
X1609783D03*
X1619783D03*
X1579783D03*
X1589783D03*
X1574783D03*
X1584783D03*
X1594783D03*
X1653030Y5500D03*
X1663030D03*
X1623030D03*
X1633030D03*
X1643030D03*
X1668030D03*
X1658030D03*
X1648030D03*
X1638030D03*
X1628030D03*
X1664783Y1369303D03*
X1654783D03*
X1644783D03*
X1634783D03*
X1624783D03*
X1649783D03*
X1659783D03*
X1629783D03*
X1639783D03*
X1703030Y5500D03*
X1713030D03*
X1673030D03*
X1683030D03*
X1693030D03*
X1718030D03*
X1708030D03*
X1698030D03*
X1688030D03*
X1678030D03*
X1697261Y1004347D03*
X1692761D03*
Y999847D03*
Y995347D03*
X1697261D03*
Y999847D03*
X1714783Y1369303D03*
X1704783D03*
X1694783D03*
X1684783D03*
X1674783D03*
X1699783D03*
X1709783D03*
X1669783D03*
X1679783D03*
X1689783D03*
X1753030Y5500D03*
X1763030D03*
X1723030D03*
X1733030D03*
X1743030D03*
X1758030D03*
X1748030D03*
X1738030D03*
X1728030D03*
X1764783Y1369303D03*
X1754783D03*
X1744783D03*
X1734783D03*
X1724783D03*
X1749783D03*
X1759783D03*
X1719783D03*
X1729783D03*
X1739783D03*
X1778030Y5500D03*
X1793030D03*
X1803030D03*
X1813030D03*
X1808030D03*
X1798030D03*
X1783030D03*
X1788030D03*
X1773030D03*
X1768030D03*
X1783806Y989468D03*
X1804783Y1369303D03*
X1794783D03*
X1784783D03*
X1774783D03*
X1799783D03*
X1809783D03*
X1769783D03*
X1779783D03*
X1789783D03*
X1843030Y5500D03*
X1853030D03*
X1863030D03*
X1838030D03*
X1858030D03*
X1848030D03*
X1823030D03*
X1833030D03*
X1828030D03*
X1818030D03*
X1862652Y846508D03*
X1850263Y964540D03*
X1850370Y960239D03*
X1845870D03*
X1845763Y964540D03*
Y956040D03*
X1850263D03*
X1825741Y969210D03*
Y974210D03*
X1840683Y969318D03*
Y974318D03*
X1825744Y986011D03*
X1840578Y985885D03*
X1844863Y983125D03*
X1853863D03*
X1858363D03*
X1849363D03*
X1862863D03*
X1853863Y978125D03*
X1844863D03*
X1849363D03*
X1862863D03*
X1858363D03*
X1825744Y991011D03*
X1840578Y990885D03*
X1854783Y1369303D03*
X1844783D03*
X1834783D03*
X1824783D03*
X1814783D03*
X1849783D03*
X1859783D03*
X1819783D03*
X1829783D03*
X1839783D03*
X1878030Y5500D03*
X1883030D03*
X1873030D03*
X1868030D03*
X1909030D03*
X1888030D03*
X1873099Y817150D03*
X1878099D03*
X1873099Y821650D03*
X1878099D03*
X1873099Y826150D03*
X1878099D03*
X1877512Y831377D03*
X1882512D03*
X1865202Y831559D03*
X1873012Y831377D03*
X1878099Y812650D03*
X1873099D03*
X1878099Y808150D03*
X1873099D03*
X1878099Y803650D03*
X1873099D03*
X1878373Y846472D03*
X1883373D03*
X1867652Y846508D03*
X1867363Y983125D03*
Y978125D03*
X1904783Y1369303D03*
X1894783D03*
X1884783D03*
X1874783D03*
X1864783D03*
X1899783D03*
X1909783D03*
X1869783D03*
X1879783D03*
X1889783D03*
X1929343Y16525D03*
Y11525D03*
Y6525D03*
X1914030Y5500D03*
X1919030D03*
X1924030D03*
X1929343Y46525D03*
Y41525D03*
Y36525D03*
Y31525D03*
Y26525D03*
Y21525D03*
Y66525D03*
Y61525D03*
Y56525D03*
Y51525D03*
Y116525D03*
Y111525D03*
Y106525D03*
Y101525D03*
Y96525D03*
Y91525D03*
Y86525D03*
Y81525D03*
Y76525D03*
Y71525D03*
Y121525D03*
Y126525D03*
Y136525D03*
Y146525D03*
Y156525D03*
Y161525D03*
Y151525D03*
Y141525D03*
Y131525D03*
Y176525D03*
Y186525D03*
Y196525D03*
Y206525D03*
Y166525D03*
Y211525D03*
Y201525D03*
Y191525D03*
Y181525D03*
Y171525D03*
Y226525D03*
Y236525D03*
Y246525D03*
Y256525D03*
Y216525D03*
Y261525D03*
Y251525D03*
Y241525D03*
Y231525D03*
Y221525D03*
Y276525D03*
Y286525D03*
Y296525D03*
Y306525D03*
Y266525D03*
Y301525D03*
Y291525D03*
Y281525D03*
Y271525D03*
Y326525D03*
Y336525D03*
Y346525D03*
Y356525D03*
Y316525D03*
Y351525D03*
Y341525D03*
Y331525D03*
Y321525D03*
Y311525D03*
Y376525D03*
Y386525D03*
Y396525D03*
Y406525D03*
Y366525D03*
Y401525D03*
Y391525D03*
Y381525D03*
Y371525D03*
Y361525D03*
Y426525D03*
Y436525D03*
Y446525D03*
Y416525D03*
Y451525D03*
Y441525D03*
Y431525D03*
Y421525D03*
Y411525D03*
Y476525D03*
Y486525D03*
Y496525D03*
Y456525D03*
Y466525D03*
Y501525D03*
Y491525D03*
Y481525D03*
Y471525D03*
Y461525D03*
Y526525D03*
Y536525D03*
Y546525D03*
Y506525D03*
Y516525D03*
Y551525D03*
Y541525D03*
Y531525D03*
Y521525D03*
Y511525D03*
Y576525D03*
Y586525D03*
Y596525D03*
Y556525D03*
Y566525D03*
Y591525D03*
Y581525D03*
Y571525D03*
Y561525D03*
Y626525D03*
Y636525D03*
Y646525D03*
Y606525D03*
Y616525D03*
Y641525D03*
Y631525D03*
Y621525D03*
Y611525D03*
Y601525D03*
Y676525D03*
Y686525D03*
Y696525D03*
Y656525D03*
Y666525D03*
Y691525D03*
Y681525D03*
Y671525D03*
Y661525D03*
Y651525D03*
Y726525D03*
Y736525D03*
Y706525D03*
Y716525D03*
Y741525D03*
Y731525D03*
Y721525D03*
Y711525D03*
Y701525D03*
Y776525D03*
Y786525D03*
Y746525D03*
Y756525D03*
Y766525D03*
Y791525D03*
Y781525D03*
Y771525D03*
Y761525D03*
Y751525D03*
Y826525D03*
Y836525D03*
Y796525D03*
Y806525D03*
Y816525D03*
Y841525D03*
Y831525D03*
Y821525D03*
Y811525D03*
Y801525D03*
Y876525D03*
Y886525D03*
Y846525D03*
Y856525D03*
Y866525D03*
Y881525D03*
Y871525D03*
Y861525D03*
Y851525D03*
Y926525D03*
Y896525D03*
Y906525D03*
Y916525D03*
Y931525D03*
Y921525D03*
Y911525D03*
Y901525D03*
Y891525D03*
Y936525D03*
Y973863D03*
Y978863D03*
Y983863D03*
Y951525D03*
Y956525D03*
Y961525D03*
Y966525D03*
Y946525D03*
Y941525D03*
Y988863D03*
Y993863D03*
Y998863D03*
Y1003863D03*
Y1008863D03*
Y1033863D03*
Y1028863D03*
Y1023863D03*
Y1018863D03*
Y1013863D03*
Y1073863D03*
Y1083863D03*
Y1043863D03*
Y1053863D03*
Y1063863D03*
Y1078863D03*
Y1068863D03*
Y1058863D03*
Y1048863D03*
Y1038863D03*
Y1123863D03*
Y1093863D03*
Y1103863D03*
Y1113863D03*
Y1128863D03*
Y1118863D03*
Y1108863D03*
Y1098863D03*
Y1088863D03*
Y1173863D03*
Y1133863D03*
Y1143863D03*
Y1153863D03*
Y1163863D03*
Y1178863D03*
Y1168863D03*
Y1158863D03*
Y1148863D03*
Y1138863D03*
Y1223863D03*
Y1183863D03*
Y1193863D03*
Y1203863D03*
Y1213863D03*
Y1228863D03*
Y1218863D03*
Y1208863D03*
Y1198863D03*
Y1188863D03*
Y1273863D03*
Y1233863D03*
Y1243863D03*
Y1253863D03*
Y1263863D03*
Y1268863D03*
Y1258863D03*
Y1248863D03*
Y1238863D03*
Y1323863D03*
Y1283863D03*
Y1293863D03*
Y1303863D03*
Y1313863D03*
Y1318863D03*
Y1308863D03*
Y1298863D03*
Y1288863D03*
Y1278863D03*
Y1333863D03*
Y1343863D03*
Y1353863D03*
X1924783Y1369303D03*
X1914783D03*
X1919783D03*
X1929343Y1358863D03*
Y1348863D03*
Y1338863D03*
Y1328863D03*
Y1363863D03*
G54D30*
X114000Y998550D03*
X180700Y586550D03*
X1755800Y1010550D03*
G54D21*
X115800Y979200D03*
X182500Y567200D03*
X1757600Y991200D03*
G54D12*
X20000Y60000D03*
Y80000D03*
Y100000D03*
Y120000D03*
Y140000D03*
Y160000D03*
Y180000D03*
Y200000D03*
Y220000D03*
Y240000D03*
Y260000D03*
Y280000D03*
Y300000D03*
Y320000D03*
Y340000D03*
Y360000D03*
Y380000D03*
Y400000D03*
Y420000D03*
Y440000D03*
X15000Y930000D03*
Y920000D03*
X25000Y930000D03*
Y920000D03*
X15000Y980000D03*
Y970000D03*
Y960000D03*
Y950000D03*
Y940000D03*
X25000D03*
Y950000D03*
Y960000D03*
Y970000D03*
Y980000D03*
X15000Y1030000D03*
Y1020000D03*
Y1010000D03*
Y1000000D03*
Y990000D03*
X25000D03*
Y1000000D03*
Y1010000D03*
Y1020000D03*
Y1040000D03*
Y1080000D03*
Y1070000D03*
Y1060000D03*
Y1050000D03*
Y1090000D03*
X19712Y1176350D03*
X25000Y1190400D03*
X17500Y1270000D03*
Y1260000D03*
Y1250000D03*
Y1240000D03*
Y1290000D03*
Y1280000D03*
Y1300000D03*
Y1310000D03*
Y1320000D03*
Y1360000D03*
Y1350000D03*
Y1330000D03*
Y1340000D03*
X60000Y20000D03*
Y40000D03*
X40000D03*
X60000Y60000D03*
X40000D03*
Y80000D03*
X60000D03*
Y100000D03*
X40000D03*
X60000Y120000D03*
X40000D03*
Y140000D03*
X60000D03*
Y160000D03*
X40000D03*
X38500Y202000D03*
X64487Y212761D03*
Y201761D03*
X53087Y179561D03*
X56000Y237000D03*
X73437Y247161D03*
X49437Y254661D03*
X73437Y234661D03*
X49937Y219661D03*
X54437D03*
X58937D03*
X62000Y276500D03*
X40000Y280000D03*
Y300000D03*
X60000D03*
Y320000D03*
X40000D03*
X60000Y340000D03*
X40000D03*
Y360000D03*
X35000Y446500D03*
X50500Y545500D03*
X58346Y516473D03*
X54088Y512336D03*
X39853Y512373D03*
X44111Y516510D03*
X47607Y527511D03*
X61834Y527515D03*
X72500Y508600D03*
X67500D03*
X40000Y560000D03*
Y580000D03*
Y600000D03*
Y620000D03*
X39000Y646000D03*
X53087Y632317D03*
X30697Y679553D03*
X73437Y687417D03*
X64487Y665417D03*
X31043Y689115D03*
X30676Y663764D03*
X58937Y672417D03*
X54437D03*
X49937D03*
X64487Y654417D03*
X27143Y663071D03*
X27510Y688422D03*
X49500Y729000D03*
X49437Y707417D03*
X73437Y699917D03*
X31064Y704904D03*
X69500Y777000D03*
X51000Y755500D03*
X38500Y800500D03*
X39000Y834500D03*
X49000Y811000D03*
X51000Y846000D03*
X40000Y930000D03*
Y920000D03*
Y970000D03*
Y960000D03*
Y950000D03*
Y940000D03*
X58175Y981325D03*
X67500Y961355D03*
X72500D03*
X50000Y1030000D03*
X70000Y1020000D03*
X40000Y1000000D03*
Y990000D03*
X50000Y1060000D03*
X47000Y1107500D03*
X64487Y1118173D03*
X30256Y1116731D03*
X30670Y1132472D03*
X58937Y1125173D03*
X54437D03*
X49937D03*
X64487Y1107173D03*
X53027Y1085073D03*
X39325Y1131400D03*
X26723Y1116038D03*
X30644Y1157871D03*
X49437Y1160173D03*
X73437Y1140173D03*
Y1152673D03*
X30623Y1142082D03*
X36848Y1173600D03*
X27090Y1141389D03*
X52000Y1186000D03*
X71500Y1205000D03*
X31500Y1224000D03*
X39425Y1226200D03*
X30000Y1190400D03*
X37225Y1230100D03*
X45800Y1306100D03*
X37500Y1360000D03*
X27500D03*
X45518Y1336366D03*
X41381Y1335567D03*
X80000Y80000D03*
X100000D03*
X120000D03*
Y100000D03*
X100000D03*
X80000D03*
X120000Y120000D03*
X100000D03*
X80000D03*
X86500Y157500D03*
X80000Y140000D03*
X118437Y141870D03*
X78500Y169500D03*
X111437Y195492D03*
X106937Y198543D03*
Y207992D03*
X111437Y165492D03*
Y180492D03*
X74937Y187461D03*
X92287Y194661D03*
X86637Y194861D03*
X95437Y176661D03*
Y181161D03*
X73937Y201661D03*
X78937D03*
X83937D03*
X88937D03*
X82000Y219000D03*
X111437Y245492D03*
Y235492D03*
X106937Y217441D03*
X111437Y265492D03*
Y275492D03*
X89237Y276861D03*
X95437Y300161D03*
X96000Y336500D03*
X80000Y320000D03*
Y340000D03*
X118437Y314114D03*
X89000Y403500D03*
X100000Y420000D03*
X120000Y440000D03*
X100000D03*
Y460000D03*
X120000D03*
Y480000D03*
X100000D03*
X120000Y500000D03*
X100000D03*
X104500Y515500D03*
X120500Y524000D03*
X86500Y522000D03*
X100000Y541500D03*
X87000Y541000D03*
X89000Y557500D03*
X108500Y572000D03*
X88000Y577500D03*
X118753Y594626D03*
X88000Y602500D03*
X111437Y648248D03*
Y633248D03*
Y618248D03*
X92287Y647417D03*
X86637Y647617D03*
X74937Y640217D03*
X85146Y621637D03*
X95437Y633917D03*
X81500Y672000D03*
X106937Y670197D03*
X111437Y688248D03*
X106937Y660748D03*
Y651299D03*
X88937Y654417D03*
X83937D03*
X78937D03*
X73937D03*
X111437Y728248D03*
Y718248D03*
Y698248D03*
X89237Y729617D03*
X75500Y757500D03*
X94000Y789000D03*
X118437Y766870D03*
X95437Y752917D03*
X89500Y802500D03*
X90000Y858000D03*
X100000Y880000D03*
Y900000D03*
X120000D03*
Y920000D03*
X100000D03*
X120000Y940000D03*
X111800Y987200D03*
Y983200D03*
X115800Y979200D03*
X119800Y971200D03*
Y975200D03*
Y979200D03*
X115800Y975200D03*
X119800Y987200D03*
Y983200D03*
X115800Y971200D03*
Y983200D03*
Y987200D03*
X119163Y959625D03*
X100000Y940000D03*
X101403Y981195D03*
X97063Y973225D03*
X98563Y977225D03*
X120000Y1025000D03*
X85000Y1020000D03*
X121914Y1003491D03*
X114100Y1002600D03*
X99700Y991400D03*
X108063Y991925D03*
X114300Y992362D03*
X104230Y992209D03*
X74000Y1074000D03*
X85000Y1060000D03*
X111437Y1071004D03*
X118437Y1047382D03*
X95537Y1082173D03*
X81000Y1124500D03*
X106937Y1122953D03*
Y1113504D03*
Y1104055D03*
X111437Y1101004D03*
Y1086004D03*
X92287Y1100173D03*
X86637Y1100373D03*
X74937Y1092973D03*
X95537Y1086673D03*
X73937Y1107173D03*
X78937D03*
X83937D03*
X88937D03*
X111437Y1171004D03*
Y1151004D03*
Y1141004D03*
X118437Y1219626D03*
X111437Y1181004D03*
X89237Y1182373D03*
X95437Y1205673D03*
X98500Y1241000D03*
X90000Y1252500D03*
X86000Y1282000D03*
X93000Y1319000D03*
X160000Y20000D03*
Y60000D03*
Y40000D03*
X140000D03*
Y60000D03*
X160000Y100000D03*
Y80000D03*
X140000D03*
Y100000D03*
X160000Y140000D03*
X140000D03*
X160000Y120000D03*
X140000D03*
X156500Y170500D03*
X130500Y211500D03*
X160500Y190000D03*
X160000Y180000D03*
X129000Y259000D03*
X142687Y237161D03*
Y248100D03*
X128000Y288500D03*
X160000Y280000D03*
X140000Y300000D03*
X160000D03*
X145437Y265561D03*
X140000Y320000D03*
X160000D03*
X140000Y440000D03*
Y460000D03*
Y480000D03*
Y500000D03*
X142500Y515500D03*
X150000Y526500D03*
X164107Y512331D03*
X168365Y516368D03*
X135000Y588000D03*
X153263Y568725D03*
X146263D03*
X144263Y573225D03*
X138763Y568725D03*
X148763Y576225D03*
X166400Y579400D03*
X168103Y569195D03*
X163763Y561225D03*
X165263Y565225D03*
X167000Y613000D03*
X147500Y605500D03*
X142687Y689917D03*
X135200Y738400D03*
X153705Y744831D03*
X153714Y720741D03*
X153757Y710653D03*
X140372Y732370D03*
X150253Y709713D03*
X145437Y717617D03*
X142687Y700767D03*
X140364Y749807D03*
X160000Y880000D03*
Y900000D03*
X140000Y920000D03*
X160000D03*
Y940000D03*
X140000D03*
X137163Y987125D03*
X130463Y983925D03*
X156000Y1032000D03*
X133063Y1012725D03*
X137063Y993725D03*
X145363Y997741D03*
X131110Y993257D03*
X134000Y1064000D03*
X153000Y1105000D03*
X132000Y1117000D03*
X148400Y1086900D03*
X142687Y1142673D03*
X154363Y1161725D03*
X153716Y1174793D03*
X145437Y1165673D03*
X150862Y1152723D03*
X142687Y1153523D03*
X170000Y1190500D03*
X153824Y1197248D03*
X153932Y1182940D03*
X148300Y1228800D03*
X148311Y1182767D03*
X135422Y1190937D03*
X140422D03*
X163500Y1345200D03*
X200000Y20000D03*
X180000D03*
X200000Y40000D03*
X180000D03*
X200000Y60000D03*
X180000D03*
Y80000D03*
X200000D03*
Y100000D03*
X180000D03*
Y120000D03*
X200000D03*
Y140000D03*
X180000D03*
X216500Y194756D03*
X210849Y194861D03*
X199149Y187461D03*
X188699Y212561D03*
Y200561D03*
X177399Y179661D03*
X198149Y201661D03*
X203149D03*
X208149D03*
X213149D03*
X206000Y219000D03*
X180500Y237000D03*
X197649Y234661D03*
X173649Y254661D03*
X197649Y247161D03*
X174149Y219661D03*
X178649D03*
X183149D03*
X180000Y300000D03*
X213449Y276861D03*
X180000Y320000D03*
Y340000D03*
X200000D03*
X178342Y512294D03*
X182600Y516331D03*
X171861Y527469D03*
X186088Y527473D03*
X196712Y508600D03*
X191712D03*
X210263Y546725D03*
X188614Y591491D03*
X182500Y559200D03*
Y571200D03*
Y575200D03*
X178500D03*
Y571200D03*
X182500Y567200D03*
X186500Y559200D03*
Y563200D03*
Y567200D03*
X182500Y563200D03*
X186500Y575200D03*
Y571200D03*
X180800Y590600D03*
X207313Y598113D03*
X203763Y581725D03*
X212063Y585741D03*
X197810Y581257D03*
X174763Y579925D03*
X203863Y575125D03*
X181000Y580362D03*
X170930Y580209D03*
X197163Y571925D03*
X210000Y644000D03*
X216499Y636917D03*
X199149Y631217D03*
X210849Y638617D03*
X185149Y617949D03*
X199763Y600725D03*
X206000Y672000D03*
X197649Y687417D03*
X210000Y650000D03*
X182259Y672559D03*
X177759D03*
X173259D03*
X198149Y654417D03*
X203149D03*
X208149D03*
X213149D03*
X213449Y729617D03*
X173649Y707417D03*
X197649Y699917D03*
X180000Y860000D03*
Y880000D03*
Y920000D03*
Y900000D03*
X199900Y923200D03*
X188706Y941328D03*
X194206D03*
X184017Y951112D03*
Y945612D03*
X198463Y945525D03*
Y951025D03*
X216712Y961155D03*
X184295Y1009469D03*
Y1014969D03*
X198741Y1014882D03*
Y1009382D03*
X188552Y1019166D03*
X215563Y1001225D03*
X203563D03*
X207563D03*
X211563D03*
X194052Y1019166D03*
X211000Y1065000D03*
X203500Y1124500D03*
X216499Y1100173D03*
X210849Y1100373D03*
X199149Y1092973D03*
X188399Y1113873D03*
Y1102873D03*
X183149Y1125173D03*
X178649D03*
X174149D03*
X177105Y1094839D03*
X195100Y1096800D03*
X198149Y1107173D03*
X203149D03*
X208149D03*
X213149D03*
X175000Y1143000D03*
X173649Y1160173D03*
X193423Y1140945D03*
X197649Y1152673D03*
X213449Y1182373D03*
X181000Y1261000D03*
X190000Y1320000D03*
X200000D03*
X210000D03*
Y1300000D03*
Y1310000D03*
X200000D03*
X190000D03*
X260000Y20000D03*
X220000D03*
X240000D03*
X260000Y60000D03*
Y40000D03*
X240000D03*
X220000D03*
Y60000D03*
X240000D03*
X260000Y100000D03*
Y80000D03*
X240000D03*
X220000D03*
Y100000D03*
X240000D03*
X260000Y140000D03*
Y120000D03*
X240000D03*
X220000D03*
X242649Y141870D03*
X262000Y209000D03*
X235649Y195492D03*
X231991Y198543D03*
X231149Y207992D03*
X235649Y165492D03*
Y180492D03*
X219749Y176661D03*
Y181361D03*
X253000Y260000D03*
X266899Y237161D03*
X235649Y245492D03*
Y235492D03*
X231149Y217441D03*
X266899Y248011D03*
X255000Y280000D03*
X235649Y265492D03*
Y275492D03*
X219649Y300161D03*
X242649Y314114D03*
X220000Y360000D03*
X240000Y380000D03*
X220000D03*
Y400000D03*
X240000D03*
Y420000D03*
X220000D03*
Y440000D03*
X240000D03*
Y460000D03*
X220000D03*
Y480000D03*
X240000D03*
Y500000D03*
X220000D03*
X265392Y539225D03*
Y533725D03*
X250586Y533920D03*
Y539420D03*
X260703Y529168D03*
X255203D03*
X220000Y520000D03*
X265275Y596896D03*
X250974Y597308D03*
X243051Y594626D03*
X265275Y602396D03*
X250974Y602808D03*
X255410Y607833D03*
X235649Y648248D03*
Y633248D03*
Y618248D03*
X260910Y607833D03*
X219749Y618917D03*
Y623417D03*
X255500Y664500D03*
X231149Y670197D03*
X235649Y688248D03*
X231149Y660748D03*
Y651299D03*
X266899Y689917D03*
X235649Y728248D03*
Y718248D03*
Y698248D03*
X264739Y732114D03*
X258600Y715500D03*
X266899Y700767D03*
X242649Y766870D03*
X219649Y752917D03*
X248500Y788500D03*
X264731Y749551D03*
X225000Y840000D03*
X245000D03*
X265000Y795000D03*
X225000Y815000D03*
Y880000D03*
X245000D03*
X225000Y860000D03*
X245000D03*
X225000Y900000D03*
X245000D03*
Y940000D03*
X239000Y985600D03*
X221712Y961155D03*
X263000Y1023000D03*
X219563Y1001225D03*
X223563D03*
X252100Y990100D03*
X244600Y1004600D03*
X261100Y1005700D03*
X227063Y994925D03*
X263000Y1047000D03*
X235649Y1071004D03*
X242649Y1047382D03*
X219749Y1082173D03*
X231149Y1122953D03*
Y1113504D03*
Y1104055D03*
X235649Y1101004D03*
Y1086004D03*
X264864Y1120500D03*
X219749Y1086873D03*
X235649Y1171004D03*
Y1151004D03*
X235300Y1142700D03*
X266899Y1141173D03*
X255000Y1207500D03*
X242649Y1219626D03*
X235649Y1181004D03*
X219649Y1205673D03*
X264594Y1190768D03*
X259594D03*
X257000Y1253000D03*
X220000Y1270000D03*
Y1320000D03*
X230000D03*
X240000D03*
X250000D03*
X260000D03*
X220000Y1280000D03*
X230000D03*
X250000Y1290000D03*
X240000D03*
X230000D03*
X220000D03*
Y1300000D03*
X230000D03*
X240000D03*
X250000D03*
X260000D03*
Y1310000D03*
X250000D03*
X240000D03*
X230000D03*
X220000D03*
X300000Y20000D03*
X280000D03*
X300000Y40000D03*
X280000Y60000D03*
Y40000D03*
X312079Y68379D03*
X303029Y68429D03*
X280000Y100000D03*
Y80000D03*
X313312Y98705D03*
X312355Y72855D03*
X313628Y112926D03*
X303000Y73500D03*
X280000Y140000D03*
Y120000D03*
X314370Y118452D03*
X314439Y133669D03*
X270000Y179500D03*
X285500Y189500D03*
X283000Y181000D03*
X314329Y212420D03*
X312912Y201661D03*
X301612Y179661D03*
X304500Y237000D03*
X297862Y254661D03*
X298362Y219661D03*
X302862D03*
X307362D03*
X300000Y300000D03*
X269649Y266261D03*
X300000Y320000D03*
Y340000D03*
X295000Y400000D03*
Y440000D03*
X291601Y418503D03*
X295000Y460000D03*
X292153Y486059D03*
X306388Y486022D03*
X302513Y512294D03*
X306771Y516331D03*
X292536Y516368D03*
X288278Y512331D03*
X296032Y527469D03*
X310259Y527473D03*
X282263Y589225D03*
X270263D03*
X274263D03*
X286263D03*
X290263D03*
X278263D03*
X293763Y582925D03*
X277000Y618500D03*
X275000Y647000D03*
X294500Y607500D03*
X284000D03*
X301612Y632417D03*
X312912Y665417D03*
X307362Y672417D03*
X302862D03*
X298362D03*
X312912Y654417D03*
X277972Y744575D03*
X297862Y707417D03*
X277981Y720485D03*
X278024Y710397D03*
X274520Y709457D03*
X286000Y810500D03*
X268100Y982300D03*
X273300Y981700D03*
X280800Y1011900D03*
X281200Y1033000D03*
X305200Y1068400D03*
X295200Y1078400D03*
Y1058400D03*
X271100Y1063200D03*
X281500Y1036744D03*
X281000Y1105000D03*
X312912Y1118273D03*
X307362Y1125173D03*
X302862D03*
X298362D03*
X313232Y1106499D03*
X301327Y1085173D03*
X304500Y1142500D03*
X302452Y1165162D03*
X278577Y1161725D03*
X277930Y1175001D03*
X269649Y1165673D03*
X275385Y1152596D03*
X271165Y1147172D03*
X306000Y1182500D03*
X278076Y1197355D03*
X278146Y1182940D03*
X315500Y1216700D03*
X276100Y1229100D03*
X273243Y1182915D03*
X286925Y1201945D03*
X301000Y1231000D03*
X295900Y1339700D03*
X296100Y1335100D03*
X279900Y1328300D03*
X283700D03*
X286100Y1349659D03*
X292600Y1337367D03*
X360000Y20000D03*
X340000D03*
X320000D03*
X360000Y40000D03*
X340000D03*
X320000D03*
X355200Y58400D03*
X346245Y58745D03*
X354100Y62100D03*
X322500Y68345D03*
X334845Y58745D03*
X317812Y98905D03*
X353001Y81799D03*
X351000Y70700D03*
X322545Y72845D03*
X361776Y70842D03*
X335081Y104081D03*
X339219Y95188D03*
X339914Y82415D03*
X344304Y82439D03*
X345321Y102400D03*
X347647Y95614D03*
X353001Y114815D03*
X347881Y114881D03*
X351416Y95788D03*
X337641Y114910D03*
X334947Y94605D03*
X342761Y114861D03*
X328000Y150500D03*
X333021Y129679D03*
X350441Y117541D03*
X337721Y129821D03*
X323813Y118512D03*
X341114Y123622D03*
X345321Y118921D03*
X323813Y133722D03*
X359862Y165492D03*
Y180492D03*
Y195492D03*
X355362Y198543D03*
Y207992D03*
X323362Y187461D03*
X340712Y194661D03*
X335062Y194861D03*
X344062Y176461D03*
X343962Y181161D03*
X322362Y201661D03*
X327362D03*
X332362D03*
X337362D03*
X333500Y219000D03*
X359862Y245492D03*
Y235492D03*
X355362Y217441D03*
X321862Y234661D03*
Y247161D03*
X359862Y265492D03*
Y275492D03*
X337662Y276861D03*
X343862Y300161D03*
X352000Y331000D03*
X320000Y340000D03*
X320474Y379474D03*
X316534D03*
X320474Y363234D03*
X316534D03*
X350000Y440000D03*
X330000D03*
X350000Y500000D03*
Y480000D03*
Y460000D03*
X330000D03*
X320925Y485385D03*
X315925D03*
X330000Y540000D03*
X350000D03*
Y520000D03*
X320925Y508600D03*
X315925D03*
X333000Y560000D03*
Y580000D03*
X350000Y560000D03*
X333000Y604000D03*
X359862Y648248D03*
Y633248D03*
Y618248D03*
X340712Y647517D03*
X335062Y647617D03*
X323362Y640217D03*
X333682Y621858D03*
X343862Y633917D03*
X330000Y672000D03*
X355362Y670197D03*
X359862Y688248D03*
X355362Y660748D03*
Y651299D03*
X321862Y687417D03*
X322362Y654417D03*
X327362D03*
X332362D03*
X337362D03*
X359862Y728248D03*
Y718248D03*
Y698248D03*
X337662Y729617D03*
X321862Y699917D03*
X355000Y780500D03*
X320000Y750000D03*
X330000Y770000D03*
X347000Y788500D03*
X343862Y752917D03*
X320474Y832229D03*
X316534D03*
X361500Y901500D03*
X330000Y900000D03*
X320925Y938140D03*
X315600Y933600D03*
X335300Y926900D03*
X360000Y960000D03*
Y940000D03*
X330000Y960000D03*
X337100Y972100D03*
X320925Y961355D03*
X315925D03*
X322000Y988500D03*
X362000Y1017000D03*
X344737Y995637D03*
X350673Y1031200D03*
X328000Y1061000D03*
X359862Y1071004D03*
X344062Y1082073D03*
X355362Y1122953D03*
Y1113504D03*
Y1104055D03*
X359862Y1101004D03*
Y1086004D03*
X340812Y1100273D03*
X335062Y1100373D03*
X323362Y1092973D03*
X344062Y1086773D03*
X322362Y1107173D03*
X327362D03*
X332362D03*
X337362D03*
X358518Y1171114D03*
X359862Y1151004D03*
Y1141004D03*
X321862Y1140173D03*
Y1152673D03*
X331679Y1175800D03*
X327500Y1197000D03*
X359862Y1181004D03*
X337662Y1182373D03*
X343862Y1205673D03*
X353000Y1231000D03*
X330000Y1302000D03*
X380000Y20000D03*
Y60000D03*
Y40000D03*
X401000Y89000D03*
X400000Y80000D03*
X365162Y88731D03*
Y77731D03*
X377144Y84720D03*
X377944Y95929D03*
X388500Y153500D03*
X395500Y160500D03*
X366862Y141870D03*
X386000Y209000D03*
X390312Y237161D03*
X390412Y248011D03*
X389000Y289000D03*
X386800Y263800D03*
X385500Y313000D03*
X366862Y314114D03*
X390000Y500000D03*
X370000D03*
X390000Y540000D03*
Y520000D03*
X370000D03*
Y540000D03*
X389000Y594500D03*
X390000Y560000D03*
X370000D03*
X366862Y594626D03*
X395000Y631000D03*
X388000Y607000D03*
X410000Y692500D03*
X379000Y664000D03*
X391112Y689917D03*
X402129Y744503D03*
X388796Y732042D03*
X402138Y720413D03*
X402181Y710325D03*
X393862Y719917D03*
X398677Y709385D03*
X391112Y700767D03*
X402500Y780500D03*
X366862Y766870D03*
X388788Y749479D03*
X407714Y761291D03*
X398254Y763517D03*
X397000Y911000D03*
X380000Y960000D03*
Y940000D03*
X393500Y988500D03*
Y1017000D03*
X408672Y1008038D03*
X390000Y1055000D03*
X366862Y1047382D03*
X388888Y1118173D03*
X391112Y1142673D03*
X399474Y1166787D03*
X385210Y1166347D03*
X393679Y1157480D03*
X383191Y1170203D03*
X391112Y1153500D03*
X366862Y1219626D03*
X406037Y1192706D03*
X402403Y1188312D03*
X398527Y1188659D03*
X383849Y1190833D03*
X388849Y1191148D03*
X398527Y1233336D03*
X437124Y212661D03*
X447574Y187461D03*
X437124Y201661D03*
X429224Y176300D03*
X446951Y213656D03*
X451951D03*
X456951D03*
X446074Y247161D03*
X422300Y254661D03*
X446074Y234661D03*
X431574Y219661D03*
X427074D03*
X422574D03*
X441645Y288847D03*
Y284647D03*
X456190Y354105D03*
X444687Y379474D03*
X440747D03*
X444687Y363234D03*
X440747D03*
X452800Y420912D03*
X418600Y445462D03*
X421700Y450200D03*
X445138Y487743D03*
X440138D03*
X450500Y459562D03*
X416303Y486022D03*
X430538Y485985D03*
X430000Y545500D03*
X460000Y540000D03*
X426663Y512257D03*
X430921Y516294D03*
X416686Y516331D03*
X412428Y512294D03*
X420182Y527432D03*
X434409Y527436D03*
X440138Y508600D03*
X445138D03*
X460000Y600000D03*
X445000D03*
X440000Y560000D03*
X460000D03*
X440000Y613000D03*
X459274Y647617D03*
X447574Y640217D03*
X425824Y632317D03*
X457853Y622091D03*
X417000Y652500D03*
X454500Y672000D03*
X446074Y687417D03*
X437224Y665417D03*
Y654417D03*
X431574Y672417D03*
X427074D03*
X422574D03*
X456574Y654417D03*
X451574D03*
X446574D03*
X452500Y744500D03*
X437500Y744000D03*
X422074Y707417D03*
X446074Y699917D03*
X455000Y780000D03*
X445000D03*
X440000Y760000D03*
X445000Y798000D03*
X444687Y832229D03*
X440747D03*
X444687Y816765D03*
X440747D03*
X445138Y938140D03*
X440138D03*
X435082Y915200D03*
X437600Y917800D03*
X445582Y925352D03*
X449137Y967757D03*
X440138Y961355D03*
X445138D03*
X428000Y988500D03*
X442600Y998300D03*
X413000Y1054200D03*
X442473Y1068726D03*
X447173D03*
X424000Y1105000D03*
X453473Y1089300D03*
X456919Y1121725D03*
X447919D03*
X452419D03*
X441976Y1107576D03*
X446627Y1112973D03*
X418500Y1176800D03*
X437104Y1160696D03*
X441400Y1169400D03*
X450500Y1208500D03*
X424000Y1206000D03*
X416900Y1221800D03*
X454500Y1248500D03*
X460000Y1320000D03*
X440000D03*
X460000Y1300000D03*
X412300Y1326200D03*
X415422Y1352000D03*
X476319Y144481D03*
X506750Y165324D03*
X480159Y201245D03*
X500184Y200328D03*
X497785Y178034D03*
X478306Y195593D03*
X461122Y194861D03*
X462200Y173109D03*
X468472Y182441D03*
X461951Y213656D03*
X484074Y245492D03*
X478651Y220734D03*
X484074Y235492D03*
Y275492D03*
X481174Y265492D03*
X461874Y276861D03*
X468074Y300161D03*
X491074Y314114D03*
X470000Y400000D03*
Y380000D03*
Y430000D03*
X465000Y491000D03*
X506746Y512331D03*
X497351Y531531D03*
X501023Y534941D03*
X499000Y553000D03*
X491074Y594626D03*
X472022Y582062D03*
X484074Y648248D03*
Y633248D03*
Y618248D03*
X464924Y647417D03*
X468174Y633917D03*
X479574Y670197D03*
X484074Y688248D03*
X479574Y660748D03*
Y651299D03*
X461574Y654417D03*
X484074Y728248D03*
Y718248D03*
Y698248D03*
X461874Y729617D03*
X461500Y769500D03*
X491074Y766870D03*
X468074Y752917D03*
X500000Y960000D03*
Y940000D03*
X480000Y960000D03*
Y940000D03*
X504000Y988500D03*
X462000D03*
X465200Y1018200D03*
X468000Y1047000D03*
X484074Y1071004D03*
X491074Y1047382D03*
X460673Y1071976D03*
X460873Y1077526D03*
X506500Y1051900D03*
X465346Y1122953D03*
X479574Y1113504D03*
Y1104055D03*
X484074Y1101004D03*
Y1086004D03*
X504724Y1118073D03*
Y1107073D03*
X484074Y1171004D03*
Y1151004D03*
Y1141004D03*
X506700Y1141973D03*
X505874Y1134773D03*
X506700Y1145973D03*
X502500Y1211500D03*
X476373Y1219498D03*
X484074Y1181004D03*
X461874Y1182373D03*
X468074Y1205673D03*
X508103Y1190557D03*
X480000Y1320000D03*
X500000Y1300000D03*
X480000D03*
Y1280000D03*
X509180Y145419D03*
X546009Y187821D03*
X539584Y184694D03*
X542155Y187543D03*
X519868Y242334D03*
X557057Y220152D03*
X553674Y220121D03*
X550219Y220111D03*
X515324Y252511D03*
X515500Y301000D03*
X550987Y262810D03*
X553742Y267705D03*
X510700Y277200D03*
X548500Y343000D03*
X515000Y322500D03*
X534905Y354105D03*
X547500Y440000D03*
X539350Y487659D03*
X534350D03*
X510621Y486059D03*
X524856Y486022D03*
X520981Y512294D03*
X549279Y513331D03*
X525579Y538331D03*
X557279Y513331D03*
X525239Y516331D03*
X511004Y516368D03*
X518700Y548700D03*
X553279Y523331D03*
X514500Y524469D03*
X528727Y524973D03*
X553279Y513331D03*
X530130Y547167D03*
X534350Y508600D03*
X539350D03*
X540000Y583000D03*
Y600000D03*
X520000D03*
X533879Y566031D03*
X548767Y556819D03*
X520579Y553231D03*
X517499Y576931D03*
X557279Y570331D03*
X527179Y568731D03*
X528000Y611000D03*
X532000Y623000D03*
X549937Y632317D03*
X515324Y689917D03*
X555787Y672417D03*
X551287D03*
X546787D03*
X526225Y744756D03*
X546287Y707417D03*
X512892Y732295D03*
X526277Y710578D03*
X526234Y720666D03*
X509996Y716996D03*
X522773Y709638D03*
X515324Y700667D03*
X509000Y772000D03*
X512884Y749732D03*
X555500Y852000D03*
X551500Y888000D03*
X523500Y883500D03*
X525000Y937000D03*
X525500Y967000D03*
X530800Y1028300D03*
X515800Y1028000D03*
X523000Y1045000D03*
X528500Y1073500D03*
X556022Y1042817D03*
X552436Y1042494D03*
X546787Y1125173D03*
X551287D03*
X555787D03*
X549773Y1085173D03*
X514474Y1107073D03*
X519474D03*
X524474D03*
X529474D03*
X546287Y1160173D03*
X535320Y1152771D03*
X534874Y1139774D03*
X526523Y1177122D03*
X526501Y1166546D03*
X509037Y1136700D03*
X524828Y1159231D03*
X526388Y1197747D03*
X526367Y1183111D03*
X522867Y1190284D03*
X513103Y1190557D03*
X522867Y1231097D03*
X539000Y1309000D03*
X520600Y1324100D03*
X518397Y1360000D03*
X512900Y1345600D03*
X603787Y207992D03*
X604517Y196263D03*
X603697Y182091D03*
X586719Y196888D03*
X568687Y187660D03*
X583487Y194861D03*
X566271Y167387D03*
X561437Y197249D03*
X592767Y179277D03*
X598236Y181981D03*
X582697Y200744D03*
X577697D03*
X572697D03*
X587697D03*
X588188Y216520D03*
X570287Y234661D03*
X563000Y217600D03*
X569009Y247887D03*
X592287Y300161D03*
X582758Y276861D03*
X590000Y342000D03*
X568899Y379474D03*
X564959D03*
X568899Y363234D03*
X564959D03*
X560000Y438500D03*
X594500Y462000D03*
X569529Y502127D03*
X575700Y528831D03*
X563279Y506731D03*
X602379Y547831D03*
X570779Y542831D03*
X568779Y512831D03*
X575779D03*
X593079Y516531D03*
Y512531D03*
X572229Y520081D03*
X580279Y512831D03*
X592000Y595000D03*
X580000Y600000D03*
X560000D03*
X571408Y577450D03*
X584279Y577431D03*
X575779D03*
X579718D03*
X592779D03*
X588779D03*
X562279D03*
X567641Y577473D03*
X571529Y562951D03*
X579529D03*
X602779Y552331D03*
X586000Y611000D03*
X589137Y647417D03*
X583487Y647617D03*
X571787Y640217D03*
X592387Y629417D03*
Y634017D03*
X579000Y672000D03*
X603787Y670197D03*
Y660748D03*
Y651299D03*
X570287Y687417D03*
X561437Y665417D03*
Y654417D03*
X585787D03*
X580787D03*
X575787D03*
X570787D03*
X559000Y741000D03*
X586087Y729617D03*
X570287Y699917D03*
X603000Y781000D03*
X592287Y752917D03*
X568899Y832229D03*
X564959D03*
X593365Y877358D03*
X592614Y882300D03*
X604000Y897000D03*
X592000Y900500D03*
X569350Y941640D03*
X564350D03*
X569350Y961355D03*
X564350D03*
X589500Y988000D03*
X571000D03*
X571400Y1000100D03*
X575000Y1057500D03*
X586500Y1061500D03*
X586000Y1046500D03*
X575000Y1046000D03*
X592387Y1082173D03*
X561337Y1120873D03*
X583487Y1100373D03*
X571787Y1092973D03*
X589137Y1100173D03*
X603787Y1122953D03*
Y1113504D03*
Y1104055D03*
X561337Y1107173D03*
X592387Y1086873D03*
X570787Y1107173D03*
X575787D03*
X580787D03*
X585787D03*
X570287Y1140173D03*
Y1152673D03*
X600640Y1171000D03*
X567500Y1189500D03*
X586087Y1182373D03*
X592287Y1205673D03*
X592400Y1214456D03*
X590000Y1247000D03*
X613500Y66000D03*
X634500Y77000D03*
X629024Y107633D03*
X607929Y112329D03*
X619171D03*
X614967Y134777D03*
X606718Y168580D03*
X639537Y237161D03*
X608287Y245492D03*
Y235492D03*
X639537Y248011D03*
X649500Y285000D03*
X608287Y275492D03*
X607961Y263934D03*
X642287Y266461D03*
X650000Y322500D03*
X615287Y314114D03*
X649000Y429500D03*
X652663Y502400D03*
X647663D03*
X612000Y502300D03*
X624028Y503558D03*
X638263Y503494D03*
X643000Y549500D03*
X620153Y511994D03*
X634388Y511957D03*
X615100Y513287D03*
X638646Y515994D03*
X624411Y516031D03*
X615119Y551586D03*
X627000Y538581D03*
Y542909D03*
X619560Y547201D03*
X627863Y522000D03*
X642509Y520667D03*
X652663Y516600D03*
X647663D03*
X615287Y594626D03*
X615147Y565956D03*
X637213Y582155D03*
X623236Y562574D03*
X608287Y648248D03*
Y633248D03*
Y618248D03*
Y688248D03*
X639537Y689917D03*
X650659Y744673D03*
X608287Y728248D03*
Y718248D03*
Y698248D03*
X637326Y732212D03*
X650668Y720583D03*
X650711Y710495D03*
X642287Y719817D03*
X647207Y709555D03*
X639537Y700767D03*
X631500Y774000D03*
X615287Y766870D03*
X637318Y749649D03*
X642000Y889500D03*
X632000Y936000D03*
X654000Y911000D03*
X646500Y898500D03*
X634000Y988000D03*
X638500Y1046500D03*
X608287Y1071004D03*
X615287Y1047382D03*
X645200Y1067800D03*
X608287Y1101004D03*
Y1086004D03*
X643000Y1146173D03*
X608287Y1171004D03*
Y1151004D03*
Y1141004D03*
X651216Y1164051D03*
X636803Y1167864D03*
X642942Y1156818D03*
X632603Y1136225D03*
X647716Y1154150D03*
X639537Y1153523D03*
X615238Y1218951D03*
X608287Y1181004D03*
X650644Y1197038D03*
X650626Y1182447D03*
X627632Y1217300D03*
X647126Y1189513D03*
X632316Y1190474D03*
X637316D03*
X700000Y60000D03*
X675000Y75500D03*
X697457Y107247D03*
X697483Y111500D03*
X661965Y106177D03*
X687566Y109568D03*
X663449Y115606D03*
X690807Y103298D03*
X658500Y184500D03*
X695137Y189130D03*
X685545Y212806D03*
X677450Y185669D03*
X685250Y199493D03*
X699950Y200846D03*
X694950D03*
X689426Y236628D03*
X694500Y247161D03*
X670500Y254661D03*
X674313Y220374D03*
X669813D03*
X673500Y344000D03*
X689232Y355251D03*
X693112Y385976D03*
X689172D03*
Y358978D03*
X698500Y415500D03*
X695500Y462500D03*
X670000Y531500D03*
X658646Y515180D03*
X696787Y580633D03*
X658681Y571798D03*
X654681D03*
X683341Y580479D03*
X689747D03*
X696000Y641717D03*
X682000Y628449D03*
X694500Y687417D03*
X685550Y665417D03*
Y654417D03*
X679929Y673058D03*
X675429D03*
X670929D03*
X700000Y654417D03*
X695000D03*
X670500Y707417D03*
X694500Y699917D03*
X691500Y778000D03*
X692500Y790500D03*
X678500Y776500D03*
X673500Y752000D03*
X677457Y944796D03*
X688563Y961355D03*
X693563D03*
X663800Y1018300D03*
X682200Y1026500D03*
X674300Y1001620D03*
X696000Y1092973D03*
X685250Y1113673D03*
Y1102873D03*
X680000Y1125173D03*
X675500D03*
X671000D03*
X674700Y1098500D03*
X695000Y1107173D03*
X700000D03*
X667700Y1160173D03*
X694500Y1140173D03*
X692671Y1152747D03*
X668000Y1195000D03*
X680500Y1208500D03*
X698500Y1306500D03*
X664000Y1278100D03*
X673000Y1354100D03*
X740000Y40000D03*
X720000D03*
Y60000D03*
X740000D03*
X724645Y138941D03*
X732500Y180492D03*
Y165492D03*
X728000Y207992D03*
Y198543D03*
X732100Y198373D03*
X707700Y194861D03*
X713350Y194661D03*
X747242Y197553D03*
X717188Y176461D03*
X716600Y181161D03*
X709950Y200846D03*
X704950D03*
X728000Y217441D03*
X732500Y245492D03*
X731048Y238563D03*
X738361Y306612D03*
X732500Y275492D03*
Y265492D03*
X710300Y276861D03*
X716500Y300161D03*
X724000Y338500D03*
X748000Y368500D03*
X726000Y369000D03*
X732000Y374500D03*
Y383000D03*
X748500Y409000D03*
X721500Y462500D03*
X727500Y476000D03*
X705348Y478425D03*
X724000Y583500D03*
X702500Y563000D03*
X739500Y594626D03*
X732500Y648248D03*
Y633248D03*
Y618248D03*
X713350Y647417D03*
X716600Y629417D03*
Y633917D03*
X704500Y672000D03*
X728000Y670197D03*
X732500Y688248D03*
X728000Y660748D03*
Y651299D03*
X707700Y649117D03*
X710000Y654417D03*
X705000D03*
X732500Y728248D03*
Y718248D03*
Y698248D03*
X710300Y729617D03*
X748000Y783000D03*
X739500Y766870D03*
X716500Y752917D03*
X745000Y833000D03*
X704500Y795000D03*
X730882Y888502D03*
X716233Y868219D03*
X733422Y857828D03*
X708683Y876958D03*
X747656Y876717D03*
X724283Y860689D03*
X737984Y861689D03*
X741883Y861389D03*
X709500Y894500D03*
X733883Y935689D03*
X736883Y938689D03*
Y929189D03*
Y933689D03*
X747383Y924689D03*
X733883Y940689D03*
X736462Y948996D03*
X736883Y943189D03*
X712000Y1046000D03*
X732500Y1071004D03*
X739500Y1047382D03*
X716600Y1081973D03*
X728000Y1122953D03*
Y1113504D03*
Y1104055D03*
X732500Y1101004D03*
Y1086004D03*
X713350Y1100173D03*
X707700Y1100373D03*
X716600Y1086673D03*
X705000Y1107173D03*
X710000D03*
X716000Y1136000D03*
X732500Y1171004D03*
Y1151004D03*
Y1141004D03*
X739500Y1219626D03*
X732500Y1181004D03*
X710300Y1182373D03*
X716500Y1205673D03*
X728174Y1275611D03*
X725678Y1272799D03*
X722790Y1270557D03*
X720446Y1267427D03*
X748500Y1287500D03*
X731500Y1277811D03*
X789045Y11615D03*
X780000Y40000D03*
X760000D03*
Y60000D03*
X780000D03*
X757020Y159692D03*
X752950Y213450D03*
X758619Y168537D03*
X767405Y210364D03*
X763188Y172500D03*
X771500Y311000D03*
X789739Y365493D03*
X764000Y439500D03*
X767500Y463500D03*
X772000Y479500D03*
X787000Y514000D03*
X798140Y630220D03*
X798210Y626440D03*
X798367Y622400D03*
X751750Y685300D03*
X754500Y668741D03*
X755000Y677700D03*
X793000Y828000D03*
Y851000D03*
X765124Y864089D03*
X766707Y872260D03*
X762453Y872413D03*
X765025Y867802D03*
X757664Y868974D03*
X753883Y929689D03*
Y937689D03*
X763883Y907689D03*
X755883D03*
X750883Y903689D03*
X753893Y912630D03*
X753883Y945689D03*
X780800Y959300D03*
X778000Y988500D03*
X762500D03*
X786800Y1016000D03*
X784000Y1024000D03*
X763000Y1075000D03*
X759500Y1056100D03*
X756250Y1140250D03*
X779535Y1180469D03*
X792263Y1178661D03*
Y1174461D03*
Y1170261D03*
X752500Y1167500D03*
X756250Y1151750D03*
X752000Y1197500D03*
X756000Y1225500D03*
X784544Y1210178D03*
Y1205978D03*
X779535Y1193469D03*
Y1189269D03*
Y1184669D03*
X797177Y1189537D03*
X797225Y1185337D03*
X792263Y1182861D03*
X770000Y1231500D03*
X769500Y1283500D03*
X792336Y1319537D03*
X769728Y1325747D03*
X777009Y1322690D03*
X781000Y1373000D03*
X772900Y1328550D03*
X784000Y1443000D03*
X796848Y1469724D03*
X829921Y-458D03*
X825984D03*
X833724Y-3346D03*
X833671Y254D03*
X806299Y-458D03*
X802362D03*
X814173D03*
X810236D03*
X822047D03*
X818110D03*
X845661Y-3642D03*
X843463Y530D03*
X802102Y51075D03*
X799102Y48575D03*
X802102Y46075D03*
X799102Y43575D03*
X802102Y41075D03*
X845961Y61762D03*
Y56762D03*
Y52762D03*
X838521Y41568D03*
X838043Y37217D03*
X806314Y35952D03*
X802350Y35923D03*
X842470Y41295D03*
X841733Y36654D03*
X818300Y39845D03*
X814300D03*
Y43845D03*
X818300D03*
X846000Y116500D03*
X810301Y78654D03*
X805301D03*
X802801Y75654D03*
X807801D03*
X812801D03*
X811500Y372000D03*
X800000Y400000D03*
X811500Y469500D03*
X846400Y469300D03*
Y473900D03*
X839000Y541000D03*
X839500Y508500D03*
Y560000D03*
X800867Y619400D03*
X803367Y622400D03*
X809015Y661000D03*
X804015D03*
X808920Y652340D03*
Y656460D03*
X806515Y664000D03*
X827500Y922500D03*
X827000Y1168000D03*
X802036Y1164244D03*
X803438Y1139700D03*
X802500Y1194500D03*
X807500D03*
X812500D03*
X810000Y1191500D03*
X805000D03*
X809600Y1236300D03*
X804600D03*
X802100Y1233300D03*
X807100D03*
X812100D03*
X806952Y1460496D03*
X806568Y1464275D03*
X802433Y1461619D03*
X800900Y1465234D03*
X800462Y1469231D03*
X839414Y1520763D03*
X834813Y1528889D03*
X834974Y1533243D03*
X882000Y-105500D03*
X885046Y20384D03*
X886322Y69D03*
X867080Y393D03*
X886427Y3802D03*
X873892Y287D03*
X886418Y-7350D03*
X849484Y649D03*
X886351Y-3735D03*
X857513Y659D03*
X861101Y66680D03*
X862099Y61626D03*
Y56626D03*
X861961Y52762D03*
X852769Y66957D03*
X848769D03*
X856769D03*
X853961Y52762D03*
X849961D03*
X857961D03*
X874244Y37026D03*
Y44935D03*
X885448Y37380D03*
X877265Y52540D03*
X881265D03*
X885265D03*
X873265D03*
X869265D03*
X869459Y56626D03*
Y61626D03*
X869044Y66985D03*
X873044D03*
X877139Y66926D03*
X885265Y60540D03*
Y56540D03*
X881750Y37397D03*
X858496Y37121D03*
X854180Y36996D03*
X852995Y40965D03*
X856995D03*
X852769Y74957D03*
X856769D03*
X861142Y71026D03*
X852810Y71303D03*
X856810D03*
X853900Y89701D03*
X886073Y78824D03*
X885464Y83201D03*
X878549Y78905D03*
Y82905D03*
X869044Y70985D03*
X873044D03*
X882549Y76905D03*
Y80905D03*
X888500Y260500D03*
X872796Y251714D03*
X850500Y266000D03*
X866000Y315000D03*
X881549Y326304D03*
X890982Y349498D03*
X874800Y355798D03*
X856500Y373000D03*
X858632Y399200D03*
X855032D03*
Y395600D03*
X858632D03*
X855032Y392000D03*
X858632D03*
X852832Y406400D03*
Y402800D03*
X856432Y406400D03*
Y402800D03*
X887100Y359100D03*
X887500Y378495D03*
X875132Y399200D03*
X878732D03*
Y395600D03*
X875132D03*
X878732Y392000D03*
X875132D03*
X880932Y406400D03*
Y402800D03*
X877332Y406400D03*
Y402800D03*
X874807Y375193D03*
X852832Y410000D03*
X856432D03*
X866276Y454900D03*
X866317Y446725D03*
X880932Y410000D03*
X877332D03*
X857300Y454300D03*
X862000Y453600D03*
X852000Y454200D03*
X866321Y451300D03*
X855500Y499500D03*
X871487Y463589D03*
X878500Y476000D03*
X878193Y467707D03*
X866278Y459562D03*
X870600Y476900D03*
X851800Y477200D03*
X860092Y542405D03*
X867500Y643000D03*
X877000Y664500D03*
X868500Y665000D03*
X868100Y685600D03*
X871700D03*
X875300D03*
X884600Y688800D03*
X881000D03*
X877400D03*
X891000Y743500D03*
X874715Y707651D03*
X871115D03*
X867515D03*
X884700Y705200D03*
X881100D03*
X877500D03*
X870500Y762500D03*
X885600Y824400D03*
X870163Y836153D03*
X865663Y834403D03*
X867663Y818831D03*
X887600Y811900D03*
X891200Y838200D03*
X878673Y804527D03*
X874569Y811300D03*
X885882Y861618D03*
X894965Y843500D03*
X877673Y868873D03*
X888962Y843262D03*
X873647Y861653D03*
X882333Y896320D03*
X895616Y985932D03*
X863800Y1309876D03*
X885301Y1358557D03*
X884746Y1350438D03*
X873495Y1370213D03*
X885300Y1371050D03*
X872164Y1350464D03*
X873259Y1365805D03*
X872181Y1354764D03*
X886792Y1404100D03*
X873918Y1411149D03*
X873800Y1418200D03*
X871432Y1420932D03*
X874900Y1421900D03*
X877406Y1419124D03*
X875740Y1415070D03*
X882226Y1404197D03*
X873694Y1404575D03*
X873700Y1375746D03*
X873570Y1380401D03*
X877300Y1432400D03*
X886500Y1432500D03*
X872192Y1424492D03*
X882000Y1432600D03*
X870921Y1432300D03*
X893158Y1516542D03*
X893050Y1489500D03*
X868791Y1478782D03*
X888800Y1493500D03*
X876514Y1514948D03*
X863851Y1501681D03*
X877828Y1500379D03*
X892966Y1508549D03*
X893036Y1512600D03*
X877946Y1496527D03*
X876096Y1505499D03*
X889002Y1489638D03*
X873972Y1472467D03*
X873922Y1477766D03*
X860179Y1491170D03*
X892682Y1520718D03*
X855092Y1535821D03*
X866621Y1544206D03*
X893020Y1566530D03*
X876200Y1553900D03*
X892700Y1543900D03*
X892558Y1528458D03*
X889300Y1551000D03*
X876190Y1537187D03*
X876100Y1549000D03*
X876200Y1558400D03*
X892700Y1524700D03*
X848551Y1542440D03*
X910500Y-137500D03*
X928600Y-115200D03*
X902000Y-58000D03*
X922687Y93D03*
X928138Y-8453D03*
X909000Y89000D03*
X898000Y133000D03*
X911000Y305500D03*
X898000Y268000D03*
X942000Y752850D03*
X897000Y839000D03*
X915000Y879000D03*
X903000Y842500D03*
X926185Y928342D03*
X924974Y933041D03*
X895869Y932822D03*
X914876Y901029D03*
X937621Y915324D03*
X920810Y902210D03*
X928100Y900650D03*
X900615Y909723D03*
X902571Y906534D03*
X903368Y934568D03*
X904594Y931141D03*
X916204Y938572D03*
X917550Y934742D03*
X901540Y937712D03*
X896679Y927505D03*
X896420Y916712D03*
X898468Y912970D03*
X931085Y936172D03*
X941274Y900845D03*
X924563Y962945D03*
X919759Y970868D03*
X938009Y987330D03*
X941868Y952101D03*
X934142Y974344D03*
X939481Y980230D03*
X912994Y971921D03*
X910397Y979189D03*
X902991Y982230D03*
X909826Y982874D03*
X905271Y974586D03*
X899846Y971468D03*
X898617Y975434D03*
X895837Y978389D03*
X896629Y982285D03*
X935623Y971054D03*
X898920Y1020000D03*
X916446Y1035438D03*
X941640Y995820D03*
X904601Y998556D03*
X910040Y1006613D03*
X911807Y1002342D03*
X919656Y998764D03*
X939544Y1003485D03*
X903442Y1003265D03*
X896371Y1002112D03*
X936378Y1035722D03*
X929257Y1035883D03*
X920770Y1067389D03*
X921149Y1062424D03*
X914948Y1063255D03*
X908477Y1061823D03*
X910387Y1055344D03*
X904875Y1051177D03*
X906000Y1222000D03*
X924500Y1236000D03*
X942925Y1369010D03*
X928384Y1346435D03*
X932559Y1360137D03*
X928439Y1360167D03*
X932564Y1346100D03*
X896500Y1341800D03*
X936959Y1360143D03*
X896212Y1345788D03*
X932294Y1379995D03*
X928194D03*
X895900Y1390100D03*
X896200Y1386000D03*
X896100Y1393800D03*
X896200Y1397900D03*
Y1405300D03*
X896100Y1401600D03*
X923829Y1389012D03*
X936994Y1379895D03*
X927601Y1384433D03*
X923486Y1384268D03*
X904941Y1456941D03*
X906600Y1461600D03*
X909400Y1459200D03*
X910000Y1464900D03*
X905500Y1467161D03*
X932500Y1493200D03*
X926500Y1499700D03*
X918500D03*
X938000Y1499200D03*
X942000Y1499500D03*
X922500Y1499700D03*
X908742Y1477427D03*
X908542Y1481127D03*
X922500Y1509700D03*
X906000Y1543700D03*
X918505Y1530405D03*
X918800Y1534500D03*
X941000Y1564200D03*
X937000D03*
X926500Y1556700D03*
X931500Y1564200D03*
X913250Y1547700D03*
X940000Y1529200D03*
X940750Y1549200D03*
X900000Y1526500D03*
X897400Y1574000D03*
X897038Y1577600D03*
X911516Y1573202D03*
X911616Y1576802D03*
X911710Y1582375D03*
X911094Y1585923D03*
X924059Y1647700D03*
X986713Y-115570D03*
X971713D03*
X981700Y-115500D03*
X976713Y-115570D03*
X991713Y-115413D03*
X989316Y-94984D03*
X992185Y-54411D03*
X989050Y-70850D03*
X975500Y11500D03*
X990565Y130230D03*
Y135230D03*
Y125230D03*
X974000Y402000D03*
X985688Y362549D03*
X974000Y523000D03*
X985500Y613500D03*
X978000Y677000D03*
X977794Y695103D03*
X952200Y742600D03*
X957100Y742900D03*
X977622Y699464D03*
X953200Y736700D03*
X956900Y737600D03*
X949048Y755225D03*
X952476Y753652D03*
X951300Y747900D03*
X956200Y748200D03*
X957320Y769818D03*
X947866Y763541D03*
X957629Y766231D03*
X952820Y769518D03*
X944500Y760750D03*
X962900Y905000D03*
X981580Y932678D03*
X953967Y933635D03*
X961100Y931640D03*
X960503Y936185D03*
X967583Y933607D03*
X968698Y928957D03*
X974484Y935078D03*
X976419Y931628D03*
X976460Y927891D03*
X981679Y936678D03*
X976213Y938846D03*
X966000Y937500D03*
X976580Y986180D03*
X948942Y974655D03*
X961134Y976191D03*
X959400Y960300D03*
X953013Y960147D03*
X947174Y957150D03*
X979020Y960000D03*
Y956200D03*
X973900Y960000D03*
Y956200D03*
X968780Y960000D03*
Y956200D03*
X987734Y979575D03*
X946138Y1006299D03*
X987970Y1004157D03*
X955700Y1030700D03*
X951200D03*
X946700D03*
X947759Y998726D03*
X961220Y1001600D03*
Y1005400D03*
X966340Y1001600D03*
Y1005400D03*
X971460Y1001600D03*
Y1005400D03*
X974020Y1026200D03*
Y1022400D03*
X968900Y1026200D03*
Y1022400D03*
X963780Y1026200D03*
X956600Y1001700D03*
Y1005700D03*
X977400Y1157900D03*
X964537Y1160310D03*
X958870Y1163617D03*
X962941Y1165929D03*
X967497Y1168802D03*
X957871Y1171219D03*
X963000Y1174427D03*
X969463Y1177599D03*
X972924Y1158033D03*
X954395Y1145604D03*
X977500Y1182300D03*
X982387Y1183598D03*
X962500Y1298500D03*
X947125Y1369010D03*
X951525Y1369107D03*
X955500Y1369000D03*
X944921Y1515200D03*
X988624Y1502923D03*
X951815Y1491459D03*
X946300Y1499300D03*
X969198Y1505851D03*
X969472Y1501978D03*
X950300Y1499500D03*
X975813Y1556916D03*
X953500Y1563200D03*
X962000Y1564200D03*
X958000D03*
X949000D03*
X945000D03*
X972001Y1533926D03*
X975813Y1545916D03*
X948750Y1549200D03*
X979963Y1545689D03*
X1034916Y-82413D03*
Y-87913D03*
X1011984Y-83066D03*
X1012174Y-88726D03*
X1004213Y-95837D03*
X998045Y-79300D03*
X993816Y-95184D03*
X1036713Y-115500D03*
X1015582Y-69800D03*
X1014800Y-62100D03*
X999300Y-64400D03*
X1009100Y-48600D03*
X1035000Y-66800D03*
X1022618Y-36900D03*
X1023300Y-44200D03*
X1032053Y-34953D03*
X1038712Y-34812D03*
X1007582Y-39418D03*
X1000300Y-74200D03*
X1032080Y-45980D03*
X1004082Y-38200D03*
X1000418Y-69982D03*
X993000Y-60600D03*
X1019118Y-34382D03*
X1019082Y-71000D03*
X1026717Y-11646D03*
X1021086Y-11682D03*
X1017600Y63600D03*
Y58900D03*
Y54200D03*
X1010650Y49950D03*
Y67650D03*
X993000Y108000D03*
X1036003Y93543D03*
X1038503Y97543D03*
X1033503D03*
Y102543D03*
Y107543D03*
Y112543D03*
X993000Y157000D03*
X1030775Y130016D03*
X1030890Y137780D03*
X993565Y137730D03*
Y132730D03*
Y127730D03*
X1030774Y133840D03*
X1030758Y126274D03*
X1030825Y122335D03*
X993000Y329000D03*
X1020250Y357188D03*
X998000Y378000D03*
X995000Y455000D03*
Y488000D03*
X1018322Y545207D03*
X1018300Y550000D03*
X993000Y635000D03*
X1025000Y817000D03*
X1028472Y834829D03*
X1027063Y850703D03*
X1031563Y852453D03*
X1038215Y877191D03*
X1034271Y876911D03*
X1011100Y904600D03*
X1025000Y897700D03*
X1036431Y929752D03*
X1037083Y933300D03*
X1016842Y916445D03*
X1014891Y943357D03*
X1013713Y974651D03*
X997694Y974940D03*
X1035947Y948800D03*
X1025774Y1001538D03*
X992994Y1005740D03*
X1012494Y1033840D03*
X1020654Y1023940D03*
X1018094Y1021240D03*
X1015534Y1023840D03*
X1007849Y1033743D03*
X996600D03*
X1012974Y1021240D03*
X1013700Y1007640D03*
X1009509Y1009850D03*
X1037282Y995028D03*
X1005294Y997940D03*
Y1001740D03*
X1010414Y997940D03*
Y1001740D03*
X1023214Y1007140D03*
X1007372Y1023832D03*
X1017194Y1033840D03*
X1018000Y1076500D03*
X1037000Y1067100D03*
X1032500D03*
X1017000Y1093950D03*
X1021200Y1094300D03*
X1031400Y1124700D03*
X1026900Y1129466D03*
X1022400Y1129183D03*
X1036160Y1095500D03*
Y1091700D03*
Y1111900D03*
X1019000Y1178000D03*
X1013400Y1137500D03*
X1021991Y1141526D03*
X1004294Y1137600D03*
X994923Y1137488D03*
X997500Y1192500D03*
X1006800Y1191200D03*
X995948Y1184250D03*
X1017354Y1196124D03*
X1021061Y1198543D03*
X1032500Y1248000D03*
X993500Y1317000D03*
X1016835Y1323916D03*
X1025335Y1324216D03*
X1031000Y1350500D03*
X1031474Y1354526D03*
X1016672Y1338228D03*
X1025284Y1341216D03*
X1025335Y1337616D03*
Y1330916D03*
X1016600Y1332000D03*
X1033000Y1416125D03*
X1028000Y1404700D03*
Y1411000D03*
X1031500Y1408000D03*
X1020854Y1455075D03*
X1016854D03*
X1065621Y-85082D03*
X1046713Y-115570D03*
X1076713D03*
X1084200Y-82300D03*
X1074400Y-81000D03*
X1051713Y-114887D03*
X1056713Y-115413D03*
X1086713Y-115570D03*
X1081713D03*
X1071713D03*
X1066713D03*
X1041713Y-115465D03*
X1085300Y-90700D03*
X1070500Y-67900D03*
X1074400Y-39100D03*
X1079600Y-50700D03*
X1087700Y-37886D03*
X1045800Y-75936D03*
X1058333Y-72770D03*
X1061325Y-40378D03*
X1054625Y-40278D03*
X1043000Y-67600D03*
X1043112Y-34912D03*
X1066600Y-72800D03*
X1066225Y-40278D03*
X1054593Y-51122D03*
X1078900Y-45782D03*
X1085800Y-57100D03*
X1070918Y-73618D03*
X1076000Y-10500D03*
X1043303Y-27685D03*
X1045873Y-24660D03*
X1043513Y-21696D03*
X1077505Y22405D03*
X1076418Y31082D03*
X1076944Y35182D03*
X1077260Y42612D03*
X1077400Y52000D03*
X1077082Y38982D03*
X1076905Y46195D03*
X1076299Y27282D03*
X1054800Y22405D03*
X1078500Y99000D03*
X1043703Y112543D03*
Y107543D03*
Y102543D03*
X1041003Y93543D03*
X1043703Y97543D03*
X1062854Y83434D03*
X1078500Y135500D03*
X1043500Y310500D03*
X1048500Y346000D03*
X1058500Y368500D03*
X1045000Y364000D03*
X1050100Y392600D03*
Y397600D03*
Y402600D03*
X1044600Y392500D03*
Y397500D03*
Y402500D03*
X1041500Y382858D03*
X1078100Y392600D03*
Y397600D03*
Y402600D03*
X1072600Y392500D03*
Y397500D03*
Y402500D03*
X1045292Y384688D03*
X1044600Y407500D03*
X1050100Y407600D03*
X1042833Y434409D03*
X1074425Y447225D03*
X1071950Y453288D03*
X1072600Y407500D03*
X1078100Y407600D03*
X1043500Y446600D03*
X1042800Y442000D03*
X1047000Y492000D03*
X1079000Y477000D03*
X1058000D03*
X1069018Y456900D03*
X1065985Y460500D03*
X1045106Y561249D03*
X1058000Y616000D03*
X1073000Y676000D03*
X1047000Y751000D03*
X1045163Y840400D03*
X1082000Y815500D03*
X1054419Y839493D03*
Y828081D03*
X1050763Y829163D03*
X1086600Y833200D03*
X1054000Y866000D03*
X1075500Y848000D03*
X1044680Y921400D03*
X1053200Y901703D03*
X1043882Y901568D03*
X1044101Y927130D03*
X1083633Y932172D03*
X1072000Y1035000D03*
X1053099Y1021657D03*
X1048512Y1021378D03*
X1041616Y997225D03*
X1052000Y1054000D03*
X1082500Y1067100D03*
X1073500D03*
X1054080Y1077680D03*
X1069000Y1067100D03*
X1064500Y1096150D03*
X1068700Y1096600D03*
X1087700Y1125800D03*
X1083355Y1125903D03*
X1070155D03*
X1048960Y1113900D03*
Y1117700D03*
X1041280Y1121500D03*
Y1113900D03*
Y1117700D03*
X1081078Y1095362D03*
X1083660Y1092700D03*
X1041280Y1095500D03*
Y1091700D03*
Y1100500D03*
X1048960Y1095500D03*
Y1091700D03*
Y1099300D03*
X1054080Y1113900D03*
Y1117700D03*
X1068700Y1108700D03*
X1083355Y1116103D03*
X1070155D03*
X1075600Y1179090D03*
X1053743Y1174221D03*
X1046900Y1168000D03*
X1052522Y1145153D03*
X1076032Y1191144D03*
X1070000Y1184100D03*
X1079500Y1276100D03*
X1047000Y1258687D03*
X1051300Y1253300D03*
X1077300Y1271700D03*
X1042343Y1324216D03*
X1048251Y1349992D03*
X1046372Y1356326D03*
X1042343Y1337616D03*
X1042443Y1342668D03*
X1042343Y1330916D03*
X1076754Y1455075D03*
X1072754D03*
X1044654D03*
X1048654D03*
X1134500Y-103500D03*
X1117535Y-115157D03*
X1115000Y-77500D03*
X1097600Y-82462D03*
X1107700Y-76800D03*
X1100929Y-90371D03*
X1116600Y-85538D03*
X1106300Y-94800D03*
X1089318Y-91682D03*
X1114400Y-55662D03*
X1093900Y-64500D03*
X1113300Y-44100D03*
X1101246Y-31005D03*
X1094200Y-38400D03*
X1094300Y-60300D03*
X1103300Y-60000D03*
X1115603Y-60293D03*
X1134110Y176500D03*
X1136203Y167600D03*
X1089300Y836100D03*
X1119159Y878130D03*
Y873130D03*
Y868130D03*
X1116159Y870630D03*
Y875630D03*
X1119419Y888607D03*
X1100847Y905617D03*
X1105847D03*
X1110847D03*
X1108347Y902617D03*
X1103347D03*
X1116419Y896107D03*
Y891107D03*
X1119419Y893607D03*
Y898607D03*
X1110447Y944217D03*
X1105447D03*
X1100447D03*
X1102947Y947217D03*
X1107947D03*
X1119700Y1067200D03*
X1124500D03*
X1091400Y1070900D03*
X1091494Y1075994D03*
X1097800Y1070700D03*
X1097500Y1075100D03*
X1103800Y1070600D03*
Y1075600D03*
X1128900Y1067200D03*
X1101580Y1091120D03*
X1107100Y1096050D03*
X1111600Y1097800D03*
X1124100Y1125100D03*
X1119500D03*
X1115000D03*
X1123600Y1096400D03*
X1123838Y1092800D03*
X1123600Y1100000D03*
X1133981Y1096283D03*
X1134002Y1092600D03*
X1134103Y1099881D03*
X1137436Y1124750D03*
X1128800Y1125100D03*
X1092200Y1125800D03*
X1103064Y1113626D03*
X1099020Y1112276D03*
X1096460Y1115125D03*
X1092742Y1113462D03*
X1134100Y1433300D03*
X1090818Y1531620D03*
X1092927Y1558887D03*
Y1555087D03*
X1095938Y1531620D03*
Y1535420D03*
X1090818D03*
X1096547Y1558887D03*
Y1555087D03*
X1139500Y-58500D03*
X1150000Y-63000D03*
X1181568Y55168D03*
X1181868Y50568D03*
Y45568D03*
X1181568Y60168D03*
X1178268Y64068D03*
X1183268D03*
X1184088Y101360D03*
X1184141Y96794D03*
X1178268Y85068D03*
Y69068D03*
Y89068D03*
X1183268Y85068D03*
Y69068D03*
Y89068D03*
X1178656Y104637D03*
X1176952Y93390D03*
X1177500Y153500D03*
X1140550Y179200D03*
X1142800Y174637D03*
X1140500Y171400D03*
X1182590Y254388D03*
X1171749Y259163D03*
X1175400Y258800D03*
X1174037Y281343D03*
X1176300Y284500D03*
X1180953Y284800D03*
X1185588Y285035D03*
X1185000Y281343D03*
X1176100Y270603D03*
X1176300Y288600D03*
X1173500Y397000D03*
X1156500Y467000D03*
X1166500Y635000D03*
X1156500Y619000D03*
X1176835Y618934D03*
X1156500Y650000D03*
X1169768Y730300D03*
Y723100D03*
Y726700D03*
X1175568Y712300D03*
X1171968D03*
X1175568Y715900D03*
X1171968D03*
X1173368Y730300D03*
X1171968Y719500D03*
X1175568D03*
X1173368Y726700D03*
Y723100D03*
X1181000Y814000D03*
X1156500Y813000D03*
X1179000Y829500D03*
X1166500D03*
X1138198Y832424D03*
X1158500Y868500D03*
X1172736Y1031786D03*
X1177036Y1032086D03*
X1144580Y1078680D03*
X1170140Y1043939D03*
X1172564Y1118373D03*
X1152880Y1097672D03*
X1152682Y1091138D03*
X1149984Y1115804D03*
X1143550Y1120317D03*
X1139524Y1121817D03*
X1152800Y1223062D03*
X1152700Y1216213D03*
X1150420Y1229800D03*
X1181400Y1266100D03*
X1184000Y1260100D03*
X1149823Y1233373D03*
X1144000Y1310000D03*
X1150232Y1316358D03*
X1154500Y1327500D03*
X1150911Y1329500D03*
X1147900Y1421500D03*
X1143900Y1431000D03*
X1142400Y1427700D03*
X1146002Y1427906D03*
X1145007Y1424446D03*
X1148556Y1425056D03*
X1153000Y1496000D03*
X1163000Y1612000D03*
X1141000Y1632000D03*
X1228500Y12500D03*
X1204768Y64368D03*
X1199768D03*
X1209768D03*
X1204068Y50368D03*
Y45368D03*
X1203768Y60568D03*
Y55568D03*
X1188268Y64068D03*
X1224000Y104000D03*
X1199768Y69368D03*
X1204768D03*
X1209768D03*
X1204768Y85368D03*
X1199768D03*
X1209768D03*
Y89368D03*
X1199768D03*
X1204768D03*
X1188268Y85068D03*
Y69068D03*
Y89068D03*
X1186500Y220500D03*
X1224800Y225200D03*
X1219917Y239646D03*
X1215600Y261800D03*
X1219962Y244739D03*
X1186600Y253200D03*
X1215547Y246355D03*
X1194700Y261700D03*
X1189700Y308527D03*
X1190200Y285023D03*
X1201835Y305319D03*
X1193800Y307857D03*
X1198100Y306858D03*
X1194600Y288237D03*
X1197000Y279400D03*
X1226045Y431102D03*
X1232500Y541000D03*
X1197868Y730300D03*
X1194268D03*
Y723100D03*
Y726700D03*
X1197868Y723100D03*
Y726700D03*
X1192068Y712300D03*
X1195668D03*
X1192068Y715900D03*
X1195668D03*
Y719500D03*
X1192068D03*
X1188000Y753000D03*
X1192000Y869000D03*
X1232700Y950400D03*
X1194000Y1037900D03*
X1229691Y1148580D03*
X1232842Y1140722D03*
X1198130Y1151410D03*
X1205303Y1227604D03*
X1214500Y1320500D03*
X1220500Y1311000D03*
X1194000Y1499000D03*
X1240500Y20000D03*
X1254000Y105000D03*
X1281500Y103500D03*
X1278421Y205974D03*
X1281603Y203340D03*
X1282106Y180492D03*
X1280800Y167200D03*
X1282287Y243489D03*
X1277606Y217441D03*
X1282106Y235492D03*
X1248193Y242618D03*
X1255600Y237300D03*
X1250016Y247017D03*
X1253300Y227700D03*
X1273200Y263700D03*
X1276200Y277400D03*
X1262075Y297100D03*
X1250500Y266600D03*
X1280000Y430000D03*
X1235796Y517450D03*
X1250011Y516707D03*
X1239362Y524168D03*
X1253511Y517606D03*
X1264878Y508068D03*
X1282106Y648248D03*
Y633248D03*
Y618248D03*
X1253800Y689600D03*
X1277606Y670197D03*
X1282106Y688248D03*
X1277606Y660748D03*
Y651299D03*
X1282106Y728248D03*
Y718248D03*
Y698248D03*
X1268400Y716100D03*
X1265891Y699583D03*
X1263250Y823436D03*
X1243200Y933700D03*
X1259808Y927260D03*
X1250475Y969248D03*
X1271296Y986867D03*
X1274413Y984613D03*
X1279599Y976407D03*
X1253338Y980784D03*
X1253975Y970147D03*
X1264269Y981248D03*
X1263618Y990606D03*
X1268378Y990608D03*
X1239900Y1024000D03*
X1256142Y1029316D03*
X1279081Y1071085D03*
X1252400Y1054100D03*
X1277606Y1122953D03*
Y1113504D03*
Y1104055D03*
X1282106Y1101004D03*
Y1086004D03*
X1251250Y1141700D03*
X1282106Y1171004D03*
Y1151004D03*
Y1141004D03*
X1246557Y1148155D03*
X1249600Y1155800D03*
X1272755Y1137293D03*
X1260300Y1169000D03*
X1240314Y1139741D03*
X1268948Y1150173D03*
X1282106Y1181004D03*
X1254800Y1269600D03*
X1257000Y1300000D03*
X1263500Y1318500D03*
X1240276Y1356700D03*
X1319000Y12000D03*
X1309000Y45500D03*
X1318500Y34500D03*
X1323829Y55929D03*
X1328295Y55800D03*
X1320055Y68000D03*
X1319100Y78800D03*
X1323521Y79179D03*
X1312999Y107280D03*
X1317661Y107896D03*
X1299569Y84272D03*
X1304563Y84309D03*
Y100771D03*
X1299569Y100639D03*
X1312263Y95463D03*
X1327921Y78900D03*
X1308228Y93399D03*
X1315961Y98112D03*
X1289000Y145400D03*
X1314794Y162944D03*
X1324134Y126967D03*
X1313127Y120839D03*
X1315118Y126967D03*
X1302074Y183779D03*
X1311200Y172661D03*
X1304293Y165909D03*
X1315838Y188804D03*
X1297507Y195492D03*
X1330807Y181473D03*
X1311750Y187911D03*
X1326637Y226568D03*
X1316637D03*
X1321637D03*
X1298700Y272800D03*
X1298500Y302900D03*
X1305000Y299400D03*
X1313000Y302900D03*
X1313915Y263541D03*
X1289000Y309500D03*
X1311000Y321000D03*
X1303500Y434000D03*
X1287000Y456000D03*
X1310000Y597000D03*
X1289106Y594626D03*
X1303800Y636417D03*
X1311200Y625417D03*
X1307500Y615417D03*
X1315400Y648017D03*
X1326500Y627917D03*
X1311750Y640667D03*
X1312000Y615417D03*
X1318000Y680417D03*
X1323000D03*
X1328000D03*
X1302500Y718917D03*
X1314000Y717417D03*
X1298500Y752417D03*
X1305000D03*
X1313000D03*
X1289106Y766870D03*
X1310500Y774700D03*
X1286000Y982200D03*
X1284695Y956586D03*
X1305000Y1041500D03*
X1289114Y1048624D03*
X1311200Y1078173D03*
X1305100Y1068173D03*
X1326500Y1080673D03*
X1317400Y1068000D03*
X1309600Y1068173D03*
X1303800Y1089173D03*
X1315300Y1100773D03*
X1311750Y1093423D03*
X1302500Y1171673D03*
X1313950Y1165990D03*
X1328000Y1133173D03*
X1318000D03*
X1323000D03*
X1300065Y1206008D03*
X1305000Y1205173D03*
X1313000D03*
X1289106Y1219626D03*
X1357500Y43500D03*
X1347500Y21000D03*
X1332500Y56500D03*
X1351200Y68600D03*
X1359350Y66350D03*
X1351201Y90099D03*
X1358355Y81488D03*
X1338215Y107586D03*
X1336034Y82542D03*
X1334383Y75892D03*
X1340961Y78811D03*
X1343521Y85472D03*
X1347607Y101337D03*
X1346081Y80671D03*
X1348641Y83326D03*
X1352351Y101724D03*
X1350779Y106496D03*
X1348641Y110550D03*
X1333281Y85133D03*
X1341922Y105649D03*
X1354500Y75400D03*
X1332934Y137712D03*
X1349931Y138361D03*
X1338400Y126015D03*
X1333988Y161471D03*
X1358971Y129978D03*
X1362685Y130109D03*
X1351665Y128325D03*
X1343112Y128997D03*
X1364017Y123277D03*
X1337662Y137188D03*
X1334500Y202548D03*
Y207548D03*
Y212548D03*
X1377463Y237100D03*
X1334500Y217548D03*
X1372274Y272874D03*
X1355991Y275272D03*
X1374338Y292900D03*
X1358573Y290900D03*
X1372000Y335000D03*
X1338000Y546500D03*
X1346363Y516578D03*
X1332148Y517321D03*
X1357316Y542311D03*
X1346057Y529857D03*
X1338100Y520300D03*
X1353500Y518900D03*
X1359882Y508014D03*
X1364882D03*
X1337500Y576500D03*
X1355700Y587600D03*
X1359700D03*
X1372272Y573560D03*
X1336000Y627000D03*
X1375463Y689917D03*
X1334000Y666417D03*
Y661917D03*
Y657417D03*
Y652917D03*
X1373553Y700994D03*
X1339500Y794000D03*
X1334329Y775831D03*
X1341219Y933282D03*
X1346080Y907004D03*
X1344000Y987500D03*
X1362000Y987000D03*
X1331070Y966090D03*
X1348796Y969488D03*
X1378100Y972100D03*
X1339404Y969600D03*
X1353762Y969886D03*
X1367382Y961355D03*
X1362382D03*
X1349829Y1014840D03*
X1365551Y1028250D03*
X1368935Y1123365D03*
X1361074Y1114565D03*
X1334500Y1104700D03*
Y1111173D03*
Y1116173D03*
Y1121173D03*
X1365461Y1136100D03*
X1375463Y1142673D03*
X1364713Y1143791D03*
X1360238Y1143867D03*
X1370716Y1148037D03*
X1351321Y1152553D03*
X1355733Y1241900D03*
X1365551Y1353500D03*
X1413268Y146062D03*
X1401819Y207992D03*
X1394705Y195413D03*
X1406319Y180492D03*
X1405100Y166000D03*
X1427663Y167032D03*
X1403963Y245492D03*
X1385051Y218684D03*
X1406000Y236700D03*
X1384475Y255839D03*
X1426713Y266161D03*
X1426400Y307400D03*
X1406319Y275492D03*
Y265492D03*
X1398493Y314114D03*
X1384713Y323200D03*
X1400000Y406000D03*
X1427000Y380000D03*
X1395300Y438500D03*
X1425000Y480000D03*
X1405000D03*
Y460000D03*
X1385000Y480000D03*
X1396500Y511000D03*
X1383500Y509500D03*
X1418493Y531407D03*
X1425600Y544600D03*
X1418507Y517007D03*
X1407936Y552099D03*
Y548099D03*
X1425200Y540100D03*
X1414319Y523900D03*
X1413319Y594626D03*
X1413400Y575000D03*
X1396297Y573397D03*
Y579803D03*
X1406319Y648248D03*
Y633248D03*
Y618248D03*
X1421500Y664000D03*
X1401819Y670197D03*
X1406319Y688248D03*
X1401819Y660748D03*
Y651299D03*
X1426713Y718917D03*
X1406319Y728248D03*
Y718248D03*
Y698248D03*
X1383952Y717435D03*
X1422713Y752417D03*
X1398245Y766870D03*
X1395000Y791500D03*
X1392355Y886696D03*
X1391000Y932400D03*
X1380300Y930200D03*
X1390000Y955500D03*
X1384800Y1002666D03*
X1390500Y1048000D03*
X1406319Y1071004D03*
X1413319Y1047382D03*
X1406319Y1086004D03*
Y1101004D03*
X1401819Y1104055D03*
X1385494Y1113504D03*
X1401819Y1122953D03*
X1406319Y1141004D03*
Y1151004D03*
Y1171004D03*
X1426713Y1171673D03*
X1383899Y1166690D03*
X1406319Y1181004D03*
X1413319Y1219626D03*
X1422713Y1205173D03*
X1388500Y1224900D03*
X1413000Y1241500D03*
X1387000Y1243500D03*
X1386500Y1258000D03*
X1418000Y1291500D03*
X1400000Y1320000D03*
X1420000D03*
X1381800Y1329600D03*
X1431713Y162661D03*
X1463804Y138605D03*
X1436204Y159247D03*
X1428013Y185956D03*
X1445994Y174086D03*
X1440300Y188000D03*
X1435963Y183833D03*
X1450713Y173049D03*
X1456373Y168971D03*
X1458764Y212625D03*
Y208025D03*
Y203425D03*
X1438186Y261287D03*
X1442213Y227661D03*
X1447213D03*
X1452213D03*
X1458764Y217225D03*
X1463000Y307000D03*
X1439300Y301500D03*
X1429800Y302500D03*
X1447170Y337890D03*
X1466500Y338100D03*
X1444238Y349852D03*
X1439654D03*
X1441770Y365790D03*
X1461100Y366000D03*
X1441970Y403990D03*
X1461300Y404200D03*
X1431909Y359311D03*
X1439500Y421500D03*
X1440000Y460000D03*
X1449576Y495482D03*
X1468605Y493549D03*
X1463000Y490638D03*
X1457200Y549600D03*
X1470700Y522100D03*
X1456439Y515000D03*
X1448261D03*
X1435200D03*
X1443700D03*
X1460200D03*
X1452200D03*
X1465700D03*
X1439200D03*
X1456450Y529600D03*
X1448450D03*
X1452279Y563600D03*
X1464700Y585600D03*
X1470000Y580000D03*
X1460274Y592498D03*
X1459200Y579600D03*
X1452200D03*
X1455750Y572350D03*
X1474700Y569100D03*
X1447700Y579600D03*
X1474700Y579100D03*
X1428013Y636417D03*
X1435413Y625417D03*
X1431713Y615417D03*
X1439713Y647917D03*
X1450713Y627817D03*
X1435963Y640667D03*
X1455202Y618557D03*
X1436213Y615417D03*
X1442213Y680417D03*
X1447213D03*
X1452213D03*
X1458713Y658417D03*
Y663417D03*
Y668417D03*
Y652217D03*
X1449000Y698000D03*
X1438087Y713756D03*
X1429213Y752417D03*
X1437213D03*
X1432000Y831000D03*
X1459500Y814000D03*
X1450500Y802500D03*
X1459500Y796500D03*
X1473000Y798000D03*
X1433500Y864500D03*
X1435300Y882700D03*
X1440500Y893500D03*
X1448000Y910000D03*
X1457500Y987500D03*
X1440000Y986500D03*
X1473008Y969646D03*
X1458967Y969535D03*
X1463616Y969265D03*
X1451800Y1004700D03*
X1433500Y1044000D03*
X1456000D03*
X1435413Y1078173D03*
X1431713Y1068173D03*
X1450713Y1080673D03*
X1446213Y1062300D03*
X1436213Y1068173D03*
X1428013Y1089173D03*
X1439713Y1100773D03*
X1442213Y1132173D03*
X1447213D03*
X1452213D03*
X1439750Y1096673D03*
X1461713Y1123173D03*
Y1118173D03*
Y1113173D03*
X1461700Y1107200D03*
X1438213Y1170173D03*
X1470953Y1152427D03*
X1475953D03*
X1429213Y1205173D03*
X1437213D03*
X1467000Y1221800D03*
X1458000Y1265500D03*
X1473600Y1242777D03*
X1460000Y1300000D03*
Y1320000D03*
X1440000D03*
X1511177Y125412D03*
X1498900Y235800D03*
X1499775Y248061D03*
X1508925Y323200D03*
X1505000Y378500D03*
X1520000Y421500D03*
X1481938Y489926D03*
X1479212Y535612D03*
X1494100Y526400D03*
X1507900Y539100D03*
X1481938Y512568D03*
X1485932Y522335D03*
X1500600Y523300D03*
X1502400Y544100D03*
X1497849Y545264D03*
X1486594Y508098D03*
X1491594D03*
X1513200Y519700D03*
X1509800Y516100D03*
X1509911Y553511D03*
X1478700Y579100D03*
X1502400Y554100D03*
X1494400Y560400D03*
Y556100D03*
X1494462Y692179D03*
X1505900Y717600D03*
X1495480Y704558D03*
X1515000Y789000D03*
X1520000Y776000D03*
X1499500Y774000D03*
Y831000D03*
X1510500Y878000D03*
X1510000Y860500D03*
X1505900Y930400D03*
X1521200Y928000D03*
X1512500Y949000D03*
X1503394Y968179D03*
X1477974Y970044D03*
X1491594Y961355D03*
X1486594D03*
X1508500Y1028500D03*
X1484000Y992315D03*
X1481500Y995758D03*
X1478194Y1017166D03*
X1481529Y1030500D03*
X1508500Y1050500D03*
X1488500Y1096000D03*
X1489096Y1131456D03*
X1489108Y1121674D03*
X1485608Y1113628D03*
X1499675Y1142673D03*
X1489333Y1147664D03*
X1504200Y1171300D03*
X1485833Y1140369D03*
X1495900Y1149000D03*
X1480000Y1320000D03*
X1491662Y1351300D03*
X1497200Y1342500D03*
X1501600Y1342300D03*
X1525336Y149369D03*
X1555925Y162661D03*
X1545383Y164116D03*
X1560000Y140000D03*
X1560425Y162661D03*
X1552225Y183661D03*
X1559625Y172661D03*
X1563925Y195261D03*
X1526031Y207992D03*
Y198543D03*
X1530531Y195492D03*
Y180492D03*
X1560175Y187911D03*
X1530531Y245492D03*
X1526031Y217441D03*
X1530142Y238021D03*
X1566425Y227661D03*
X1571425D03*
X1550925Y266161D03*
X1546925Y299661D03*
X1553425D03*
X1561425D03*
X1562425Y264661D03*
X1530531Y275492D03*
Y265492D03*
X1537531Y314114D03*
X1545000Y455000D03*
X1560000D03*
X1525000D03*
X1568500Y438500D03*
X1545000Y475000D03*
X1560000D03*
Y500000D03*
Y525000D03*
X1568500Y544100D03*
X1568000Y548500D03*
X1552000Y584500D03*
X1566000Y595000D03*
X1537531Y594626D03*
X1552225Y636417D03*
X1559625Y625417D03*
X1555925Y615417D03*
X1530531Y648248D03*
Y633248D03*
Y618248D03*
X1555175Y642667D03*
X1560425Y615417D03*
X1558925Y650017D03*
X1526031Y670197D03*
X1530531Y688248D03*
X1526031Y660748D03*
Y651299D03*
X1566425Y677417D03*
X1571425D03*
X1565593Y654856D03*
X1565618Y660773D03*
Y665773D03*
Y670773D03*
X1550925Y718917D03*
X1562425Y717417D03*
X1530531Y728248D03*
Y718248D03*
Y698248D03*
X1526000Y728000D03*
X1555000Y770000D03*
X1546925Y752417D03*
X1553425D03*
X1561425D03*
X1537531Y766870D03*
X1525000Y878000D03*
X1570500Y888400D03*
X1564500Y931000D03*
X1548500Y933000D03*
X1564000Y949000D03*
X1552500Y1028000D03*
X1557500Y1043500D03*
X1537531Y1047382D03*
X1559625Y1078173D03*
X1555925Y1068173D03*
X1530531Y1071004D03*
X1570425Y1062000D03*
X1560425Y1068173D03*
X1552225Y1089173D03*
X1526031Y1122953D03*
Y1113504D03*
Y1104055D03*
X1530531Y1101004D03*
Y1086004D03*
X1547800Y1098819D03*
X1552800D03*
X1557800D03*
X1562800D03*
X1550925Y1171673D03*
X1552575Y1139700D03*
X1562425Y1170173D03*
X1530531Y1171004D03*
Y1151004D03*
X1528723Y1138918D03*
X1556231Y1134920D03*
X1546898Y1204827D03*
X1553425Y1208897D03*
X1561425Y1205173D03*
X1537879Y1219626D03*
X1530531Y1181004D03*
X1558650Y1217426D03*
X1600000Y20000D03*
X1620000D03*
X1580000D03*
X1600000Y60000D03*
X1620000Y40000D03*
X1600000D03*
X1580000D03*
Y60000D03*
X1620000Y100000D03*
X1600000Y80000D03*
X1620000D03*
X1580000D03*
X1620000Y140000D03*
Y120000D03*
X1585757Y134147D03*
X1607000Y199000D03*
X1574925Y175061D03*
X1579371Y166019D03*
X1582925Y210661D03*
Y205661D03*
Y200661D03*
X1595500Y258500D03*
X1621100Y240561D03*
X1608000Y256000D03*
X1576425Y227661D03*
X1621100Y244661D03*
X1582925Y215661D03*
X1600000Y340000D03*
X1620000D03*
Y320000D03*
X1600000D03*
X1579500Y331000D03*
X1597245Y516662D03*
X1583030Y517405D03*
X1586596Y518723D03*
X1600745Y517561D03*
X1615807Y508600D03*
X1610807D03*
X1573000Y565500D03*
X1574925Y627817D03*
X1578926Y618657D03*
X1576425Y677417D03*
X1620469Y697517D03*
X1580000Y780000D03*
X1576500Y928500D03*
X1584800Y895800D03*
X1587400Y912200D03*
X1608200Y914400D03*
X1618200Y916800D03*
X1597221Y969572D03*
X1583180Y969461D03*
X1574576Y976700D03*
X1615494Y973179D03*
X1587829Y969191D03*
X1602187Y969970D03*
X1615807Y961355D03*
X1610807D03*
X1596000Y990000D03*
X1580381Y1007066D03*
X1602400Y1019366D03*
X1620059Y1032932D03*
X1611500Y1078000D03*
X1593000Y1043500D03*
X1574925Y1080673D03*
X1603425Y1105040D03*
Y1100040D03*
X1598425Y1102440D03*
Y1107440D03*
X1620059Y1128071D03*
X1615909Y1150262D03*
X1593500Y1185500D03*
X1581500Y1240000D03*
X1613400Y1236500D03*
X1600000Y1320000D03*
X1640000Y20000D03*
X1660000D03*
X1640000Y60000D03*
X1660000D03*
Y40000D03*
X1640000D03*
Y100000D03*
X1660000D03*
X1640000Y80000D03*
X1660000D03*
Y120000D03*
X1640000D03*
X1661744Y141870D03*
X1650244Y207992D03*
Y198543D03*
X1654744Y195492D03*
Y180492D03*
Y165492D03*
Y245492D03*
X1650244Y217441D03*
X1654744Y235492D03*
X1652387Y277343D03*
X1653789Y267766D03*
X1622738Y264938D03*
X1639000Y320000D03*
X1640000Y340000D03*
X1660000D03*
X1661744Y314114D03*
X1660000Y400000D03*
X1640000Y360000D03*
X1660000Y440000D03*
Y480000D03*
X1640000D03*
Y460000D03*
X1660000D03*
X1640000Y500000D03*
X1660000D03*
Y520000D03*
X1640000D03*
X1660000Y540000D03*
X1640000D03*
Y560000D03*
X1660000D03*
X1661744Y594626D03*
X1654744Y648248D03*
Y633248D03*
Y618248D03*
X1623888Y689917D03*
X1652962Y670204D03*
X1654744Y688248D03*
X1650244Y660748D03*
Y651299D03*
X1637000Y729000D03*
X1638000Y740000D03*
X1654744Y728248D03*
Y718248D03*
Y698248D03*
X1621138Y719238D03*
X1630000Y780000D03*
Y760000D03*
X1661744Y766870D03*
X1625000Y800000D03*
X1643344Y887455D03*
X1646013Y884255D03*
X1639644Y889755D03*
X1651500Y913500D03*
X1633600Y936300D03*
X1621787Y917108D03*
X1636400Y925800D03*
X1650000Y950000D03*
Y980000D03*
X1629094Y975179D03*
X1653500Y1016500D03*
X1650000Y1000000D03*
X1632000Y1049500D03*
X1654744Y1071004D03*
X1661744Y1047382D03*
X1650244Y1122953D03*
Y1113504D03*
Y1104055D03*
X1654744Y1101004D03*
Y1086004D03*
X1627563Y1132075D03*
X1627802Y1118949D03*
X1627769Y1110037D03*
X1624198Y1111309D03*
X1635688Y1141158D03*
X1650841Y1168660D03*
X1654744Y1151004D03*
Y1141004D03*
X1627197Y1143044D03*
X1633138Y1165673D03*
X1635688Y1153773D03*
X1661744Y1219626D03*
X1668378Y1181004D03*
X1640000Y1260000D03*
X1660000D03*
X1640000Y1320000D03*
Y1300000D03*
X1660000Y1320000D03*
Y1300000D03*
Y1280000D03*
X1640000D03*
X1624500Y1349100D03*
X1700000Y20000D03*
X1680000D03*
X1700000Y60000D03*
Y40000D03*
X1680000Y60000D03*
Y40000D03*
Y100000D03*
Y80000D03*
X1700000Y100000D03*
Y80000D03*
Y140000D03*
Y120000D03*
X1680000D03*
X1679500Y144000D03*
X1680138Y162661D03*
X1684638D03*
X1676438Y183661D03*
X1683838Y172661D03*
X1688138Y195261D03*
X1684388Y187911D03*
X1699138Y175061D03*
X1703584Y166019D03*
X1707138Y210661D03*
Y205661D03*
Y200661D03*
X1690638Y227661D03*
X1695638D03*
X1700638D03*
X1707138Y215661D03*
X1675475Y267424D03*
X1671138Y299661D03*
X1677638D03*
X1685638D03*
X1686638Y264661D03*
X1678500Y320000D03*
X1700000Y400000D03*
X1680000Y380000D03*
X1700000Y360000D03*
X1680000Y440000D03*
Y420000D03*
X1700000Y440000D03*
Y420000D03*
Y460000D03*
X1680000Y480000D03*
Y460000D03*
Y500000D03*
Y520000D03*
X1700000Y540000D03*
X1680000D03*
X1707495Y517152D03*
X1711061Y518470D03*
X1700000Y560000D03*
X1680000D03*
X1676438Y636417D03*
X1683838Y625417D03*
X1680138Y615417D03*
X1688138Y648017D03*
X1684388Y638324D03*
X1699138Y627917D03*
X1705000Y618667D03*
X1684638Y615417D03*
X1699638Y675417D03*
X1689638D03*
X1694638D03*
X1707100Y652500D03*
X1707138Y658417D03*
Y663417D03*
Y668417D03*
X1675138Y718917D03*
X1686638Y717417D03*
X1710000Y770000D03*
Y785000D03*
X1685000Y770000D03*
X1671138Y752417D03*
X1677638D03*
X1685638D03*
X1709000Y915000D03*
X1687000Y905500D03*
X1692100Y923600D03*
X1704010Y898000D03*
X1716500Y943500D03*
X1674814Y961977D03*
X1677056Y954636D03*
X1680012Y952402D03*
X1706000Y1022000D03*
X1717681Y1006054D03*
X1712181Y1001554D03*
X1685047Y1014966D03*
X1680087Y1023983D03*
X1671422Y1009266D03*
X1690279Y1011526D03*
X1691771Y1035163D03*
X1683838Y1078173D03*
X1680138Y1068173D03*
X1699138Y1080573D03*
X1685100Y1054000D03*
X1679300Y1043169D03*
X1694638Y1063600D03*
X1684638Y1068173D03*
X1688138Y1100773D03*
X1676438Y1089173D03*
X1700638Y1131673D03*
X1695638D03*
X1690638D03*
X1684388Y1091723D03*
X1707138Y1111173D03*
Y1116173D03*
Y1121173D03*
X1707200Y1105200D03*
X1686638Y1170173D03*
X1675138Y1171673D03*
X1685638Y1205173D03*
X1677638D03*
X1671138D03*
X1702838Y1215300D03*
X1680000Y1240000D03*
X1700000Y1260000D03*
X1680000D03*
X1710617Y1231429D03*
X1715049Y1234000D03*
X1700000Y1320000D03*
Y1300000D03*
Y1280000D03*
X1680000Y1320000D03*
Y1300000D03*
Y1280000D03*
X1760000Y20000D03*
X1740000D03*
X1720000D03*
X1760000Y60000D03*
Y40000D03*
X1740000D03*
Y60000D03*
X1720000Y40000D03*
Y60000D03*
X1740000Y100000D03*
X1760000D03*
X1740000Y80000D03*
X1760000D03*
X1720000Y100000D03*
Y80000D03*
X1740000Y140000D03*
X1760000Y120000D03*
X1740000D03*
X1720000Y140000D03*
Y120000D03*
X1728500Y249500D03*
X1746600Y240561D03*
X1760486Y217441D03*
X1746400Y244561D03*
X1763500Y288000D03*
X1720000Y300000D03*
Y280000D03*
X1747550Y265000D03*
X1720000Y340000D03*
X1760000D03*
X1740000Y320000D03*
X1760000Y440000D03*
Y420000D03*
Y500000D03*
Y480000D03*
Y460000D03*
X1740000Y540000D03*
X1760000D03*
Y520000D03*
X1721710Y516409D03*
X1725100Y519300D03*
X1740019Y508600D03*
X1735019D03*
X1745000Y670000D03*
Y690000D03*
Y660000D03*
X1730000Y690000D03*
Y670000D03*
Y730000D03*
Y710000D03*
X1735000Y785000D03*
X1730000Y775000D03*
Y750000D03*
X1725000Y800000D03*
X1718000Y876000D03*
X1752000Y929200D03*
X1759884Y969161D03*
X1757600Y987200D03*
X1761600D03*
Y983200D03*
X1757600D03*
X1742001Y965464D03*
X1755010Y966285D03*
X1740019Y961355D03*
X1735019D03*
X1738863Y985225D03*
X1761600Y991200D03*
Y999200D03*
Y995200D03*
X1757600Y991200D03*
X1753600Y995200D03*
Y999200D03*
X1757600D03*
Y995200D03*
X1726681Y1001554D03*
X1719681D03*
X1722181Y1009054D03*
X1763714Y1015491D03*
X1755900Y1014600D03*
X1740499Y1008223D03*
X1749863Y1003925D03*
X1756100Y1004362D03*
X1746030Y1004209D03*
X1737241Y997843D03*
X1740363Y989225D03*
X1755000Y1045000D03*
X1725000D03*
X1745000Y1100000D03*
X1759055Y1113504D03*
X1736725Y1123446D03*
X1733245Y1115503D03*
X1748100Y1142673D03*
X1736871Y1158178D03*
X1736941Y1141871D03*
X1751400Y1173900D03*
X1732768Y1141697D03*
X1748100Y1153673D03*
X1718117Y1152553D03*
X1723117D03*
X1728000Y1204500D03*
X1755900Y1212704D03*
X1720000Y1320000D03*
X1760000D03*
X1753000Y1302000D03*
X1740000Y1346900D03*
X1780000Y60000D03*
Y40000D03*
X1800000Y100000D03*
Y80000D03*
X1780000Y100000D03*
Y80000D03*
X1800000Y120000D03*
X1780000D03*
X1785956Y141870D03*
X1804350Y162661D03*
X1808850D03*
X1801988Y183904D03*
X1808050Y172661D03*
X1812350Y195261D03*
X1774456Y207992D03*
Y198543D03*
X1778956Y195492D03*
Y180492D03*
X1775140Y165728D03*
X1808600Y187911D03*
X1778956Y245492D03*
Y235492D03*
X1799350Y266161D03*
X1795350Y299661D03*
X1801850D03*
X1809850D03*
X1810850Y264661D03*
X1778956Y275492D03*
Y265492D03*
X1785956Y314114D03*
X1800000Y440000D03*
X1780000D03*
X1800000Y500000D03*
X1780000D03*
X1800000Y480000D03*
Y460000D03*
X1780000Y480000D03*
Y460000D03*
X1800000Y540000D03*
X1780000D03*
X1800000Y520000D03*
X1780000D03*
X1800000Y560000D03*
X1785956Y594626D03*
X1800650Y636417D03*
X1808050Y625417D03*
X1804350Y615417D03*
X1812350Y648017D03*
X1778956Y648248D03*
Y633248D03*
Y618248D03*
X1808600Y640667D03*
X1808850Y615417D03*
X1774456Y670197D03*
X1778956Y688248D03*
X1774456Y660748D03*
Y651299D03*
X1799326Y717506D03*
X1811474Y717423D03*
X1778956Y728248D03*
Y718248D03*
Y698248D03*
X1766721Y716500D03*
Y720500D03*
X1795468Y752594D03*
X1801968D03*
X1809968D03*
X1785956Y766870D03*
X1773500Y879500D03*
X1813851Y927406D03*
X1771000Y944500D03*
X1799000Y945500D03*
X1788361Y964676D03*
X1799051Y963346D03*
X1768692Y966073D03*
X1797463Y968652D03*
X1806077Y961860D03*
X1782666Y961344D03*
X1777666D03*
X1783778Y970371D03*
X1774863Y1024725D03*
X1788726Y1034726D03*
X1778863Y1005725D03*
X1787163Y1009741D03*
X1772863Y1005304D03*
X1778963Y999125D03*
X1772263Y995925D03*
X1785956Y1047382D03*
X1808050Y1078173D03*
X1800750Y1067973D03*
X1778956Y1071004D03*
X1812050Y1071223D03*
X1805250Y1067973D03*
X1800650Y1089173D03*
X1811968Y1100773D03*
X1774456Y1122953D03*
Y1104055D03*
X1778956Y1101004D03*
Y1086004D03*
X1799350Y1171673D03*
X1810850Y1170173D03*
X1778956Y1171004D03*
Y1151004D03*
Y1141004D03*
X1795350Y1205173D03*
X1801850D03*
X1809850D03*
X1785956Y1219626D03*
X1778956Y1181004D03*
X1772111Y1232695D03*
X1860000Y60000D03*
Y80000D03*
Y100000D03*
X1840000D03*
X1820000D03*
X1860000Y140000D03*
Y120000D03*
X1840000D03*
X1820000Y140000D03*
Y120000D03*
X1859017Y161725D03*
X1841021Y152968D03*
X1845517Y158475D03*
X1859117Y167375D03*
X1851717Y179075D03*
X1856219Y212661D03*
Y201661D03*
X1823350Y175161D03*
X1827796Y166019D03*
X1831350Y210661D03*
Y205661D03*
Y200661D03*
X1841169Y254661D03*
X1850669Y219661D03*
X1846169D03*
X1841669D03*
X1824850Y227661D03*
X1819850D03*
X1814850D03*
X1831350Y215661D03*
X1840000Y340000D03*
Y320000D03*
X1860000D03*
X1820000D03*
Y440000D03*
Y480000D03*
Y460000D03*
X1840000Y540000D03*
X1820000D03*
X1845545Y516536D03*
X1831330Y517279D03*
X1834896Y518597D03*
X1849045Y517435D03*
X1859232Y508600D03*
X1840000Y580000D03*
X1820000D03*
X1840000Y560000D03*
X1820000D03*
X1858917Y614481D03*
X1859117Y620131D03*
X1851717Y635331D03*
X1823350Y627917D03*
X1827667Y618703D03*
X1840855Y606200D03*
X1845417Y611231D03*
X1862200Y686700D03*
X1856219Y665417D03*
X1841669Y672417D03*
X1846169D03*
X1850669D03*
X1814850Y680417D03*
X1819850D03*
X1824850D03*
X1856219Y654417D03*
X1831350Y658417D03*
Y663417D03*
Y668417D03*
X1831300Y652600D03*
X1850000Y745000D03*
X1837576Y707417D03*
X1820000Y780000D03*
X1848491Y819787D03*
Y823787D03*
Y815787D03*
Y807787D03*
X1850151Y835119D03*
X1850177Y838746D03*
X1838239Y831626D03*
X1845579Y831731D03*
X1838311Y827911D03*
X1845651Y828016D03*
X1848491Y811787D03*
X1855676Y800787D03*
X1824170Y886349D03*
X1860276Y916059D03*
Y912059D03*
X1843731Y936066D03*
X1819541Y921500D03*
X1823937Y890883D03*
X1821152Y907899D03*
X1843811Y940067D03*
X1840419Y945557D03*
Y951057D03*
X1825945Y945449D03*
Y950949D03*
X1830665Y941751D03*
X1836165D03*
X1825971Y1015512D03*
Y1010012D03*
X1840445Y1015620D03*
Y1010120D03*
X1835895Y1020064D03*
X1830395D03*
X1857363Y1002625D03*
X1845363D03*
X1849363D03*
X1861363D03*
X1853363D03*
X1823350Y1080673D03*
X1856437Y1106400D03*
X1858046Y1092779D03*
X1836953Y1103391D03*
X1850363Y1115037D03*
X1847506Y1118794D03*
X1851565Y1118784D03*
X1850280Y1111373D03*
X1816046Y1098532D03*
X1836200Y1130000D03*
X1828850Y1106173D03*
Y1111173D03*
Y1116173D03*
Y1121173D03*
X1850532Y1153286D03*
X1836231Y1140669D03*
X1824850Y1133173D03*
X1814850D03*
X1819850D03*
X1840585Y1151653D03*
X1836400Y1151900D03*
X1860000Y1320000D03*
X1880000Y60000D03*
X1900000D03*
X1880000Y80000D03*
X1900000D03*
Y100000D03*
X1880000D03*
X1900000Y120000D03*
X1880000Y140000D03*
Y120000D03*
X1910169Y141870D03*
X1898669Y207992D03*
Y198543D03*
X1903169Y195492D03*
Y180492D03*
Y165492D03*
X1885204Y184345D03*
X1869500Y179134D03*
X1876938Y181062D03*
X1865669Y201661D03*
X1870669D03*
X1875669D03*
X1880669D03*
X1873500Y219000D03*
X1865169Y247161D03*
Y234661D03*
X1903169Y245492D03*
X1898669Y217441D03*
X1903169Y235492D03*
X1881088Y296184D03*
X1903169Y275492D03*
Y265492D03*
X1880969Y276861D03*
X1880000Y340000D03*
Y320000D03*
X1910169Y314114D03*
X1890000Y400000D03*
Y380000D03*
Y360000D03*
Y440000D03*
Y420000D03*
X1864232Y508600D03*
X1910169Y594626D03*
X1903169Y648248D03*
Y633248D03*
Y618248D03*
X1885300Y636800D03*
X1869500Y633500D03*
X1878900Y637000D03*
X1898669Y670197D03*
X1903169Y688248D03*
X1898669Y660748D03*
Y651299D03*
X1879669Y652917D03*
X1874669D03*
X1869669D03*
X1864669D03*
X1903169Y728248D03*
Y718248D03*
Y698248D03*
X1880969Y729617D03*
X1865169Y699917D03*
X1880000Y780000D03*
X1910169Y766870D03*
X1887169Y752917D03*
X1908107Y831894D03*
X1902607D03*
X1907999Y846368D03*
X1902499D03*
X1884800Y890750D03*
X1902441Y888500D03*
X1892443Y894350D03*
X1872276Y916059D03*
X1876276D03*
Y920059D03*
X1872276D03*
X1868276Y916059D03*
X1864276Y912059D03*
X1868276D03*
X1864276Y916059D03*
X1876276Y912059D03*
X1872276D03*
X1884200Y895000D03*
X1896943Y894350D03*
X1891676Y917759D03*
X1884500Y912500D03*
X1904000Y933500D03*
Y929000D03*
Y925000D03*
X1906500Y893400D03*
X1909358Y897500D03*
X1904000Y938000D03*
X1873001Y901396D03*
X1904000Y921000D03*
X1872190Y936766D03*
X1875801Y946796D03*
X1875769Y951122D03*
X1880122Y954062D03*
X1880383Y950341D03*
X1865363Y1002625D03*
X1867963Y996425D03*
X1868100Y1055410D03*
X1871000Y1073300D03*
X1903169Y1071004D03*
X1910169Y1047382D03*
X1884835Y1067400D03*
X1887402Y1050193D03*
X1872162Y1055426D03*
X1864617Y1040934D03*
X1888085Y1059938D03*
X1876662Y1055426D03*
X1863700Y1085000D03*
X1898669Y1122953D03*
Y1113504D03*
Y1104055D03*
X1903169Y1101004D03*
Y1086004D03*
X1864833Y1091419D03*
X1870779Y1091763D03*
X1875779D03*
X1880779D03*
X1863131Y1133108D03*
X1903169Y1171004D03*
X1903100Y1149700D03*
X1903169Y1141004D03*
X1864352Y1153308D03*
X1871174Y1138730D03*
X1887169Y1205673D03*
X1910169Y1219626D03*
X1903169Y1181004D03*
X1880969Y1182373D03*
X1900000Y1260000D03*
Y1280000D03*
Y1320000D03*
Y1300000D03*
X1873500Y1329000D03*
X1920000Y60000D03*
Y80000D03*
Y100000D03*
Y120000D03*
X1912551Y836444D03*
Y841944D03*
X1911676Y893469D03*
X1920000Y1260000D03*
Y1280000D03*
Y1320000D03*
Y1300000D03*
G54D13*
X31496Y882677D03*
X168307Y646457D03*
X660236D03*
X718110Y820866D03*
X1366142Y646457D03*
X1462992Y866929D03*
X1602756Y646457D03*
X1903346Y803937D03*
G54D22*
X106157Y985106D03*
Y983137D03*
Y981169D03*
Y979200D03*
Y977231D03*
Y975263D03*
Y973294D03*
Y971326D03*
Y969357D03*
Y989043D03*
Y987074D03*
X125443Y969357D03*
Y971326D03*
Y973294D03*
Y975263D03*
Y977231D03*
Y979200D03*
Y981169D03*
Y983137D03*
Y985106D03*
Y987074D03*
Y989043D03*
X172857Y577043D03*
Y575074D03*
Y573106D03*
Y571137D03*
Y569169D03*
Y567200D03*
Y565231D03*
Y563263D03*
Y561294D03*
Y559326D03*
Y557357D03*
X192143D03*
Y559326D03*
Y561294D03*
Y563263D03*
Y565231D03*
Y567200D03*
Y569169D03*
Y571137D03*
Y573106D03*
Y575074D03*
Y577043D03*
X1747957Y985294D03*
Y983326D03*
Y981357D03*
Y1001043D03*
Y999074D03*
Y997106D03*
Y995137D03*
Y993169D03*
Y991200D03*
Y989231D03*
Y987263D03*
X1767243Y981357D03*
Y983326D03*
Y985294D03*
Y987263D03*
Y989231D03*
Y991200D03*
Y993169D03*
Y995137D03*
Y997106D03*
Y999074D03*
Y1001043D03*
G54D31*
X114000Y996050D03*
X180700Y584050D03*
X1755800Y1008050D03*
G54D40*
X128863Y1001725D03*
X195563Y589725D03*
X1770663Y1013725D03*
X1850800Y904000D03*
X1868300Y936500D03*
G54D41*
X154856Y1002801D03*
X221556Y590801D03*
X749461Y868854D03*
X726225Y873544D03*
X1796656Y1014801D03*
X1850800Y907500D03*
G54D23*
X95363Y987725D03*
X87763D03*
X129700Y548400D03*
X137300D03*
X162063Y575725D03*
X154463D03*
X741782Y938102D03*
X749382D03*
X741782Y930302D03*
X749382D03*
X741782Y946002D03*
X749382D03*
X863032Y396400D03*
X870632D03*
X1057358Y394574D03*
X1064958D03*
X1735481Y1008554D03*
X1727881D03*
X1861617Y808535D03*
X1854017D03*
X1861617Y816335D03*
X1854017D03*
X1861617Y824135D03*
X1854017D03*
X1850800Y918500D03*
X1843200D03*
X1855800Y934500D03*
X1848200D03*
X1855200Y958500D03*
X1862800D03*
X1855800Y942500D03*
X1848200D03*
X1862700D03*
Y950500D03*
X1855800D03*
X1848200D03*
X1870300Y942500D03*
Y950500D03*
G54D50*
X745983Y864989D03*
X714054Y876958D03*
X738282Y904102D03*
X859600Y458600D03*
X967800Y1516700D03*
Y1520700D03*
X1896800Y933500D03*
Y929000D03*
G54D32*
X79563Y994472D03*
X140385Y572680D03*
X146263Y582472D03*
X126711Y959847D03*
X156063Y1007725D03*
X142563Y1006625D03*
X134063Y1003225D03*
X209163Y594425D03*
X200763Y591225D03*
X222763Y595725D03*
X223100Y920600D03*
X289510Y1342259D03*
X447533Y475900D03*
X458679Y470700D03*
X429613Y1017920D03*
X432657Y1015102D03*
X422373Y1359747D03*
X418922Y1356522D03*
X462133Y473300D03*
X481533Y480875D03*
X536000Y1359826D03*
X541362D03*
X553587Y1346026D03*
X527000Y1340600D03*
X521500Y1342800D03*
X585479Y537731D03*
Y543994D03*
X609334Y538306D03*
Y543306D03*
X631540Y589451D03*
X658574Y930100D03*
X699883Y916689D03*
X700383Y940189D03*
X706084Y881450D03*
X746800Y872700D03*
X713883Y890189D03*
X727883Y877189D03*
X743000Y886200D03*
X737687Y872489D03*
X743200Y881658D03*
X731866Y873789D03*
X740883Y920189D03*
X740383Y911689D03*
X737683Y899989D03*
X746183Y901389D03*
X743883Y893289D03*
X768770Y868643D03*
X776400Y956500D03*
X782230Y1323670D03*
X785340Y1320410D03*
X789549Y1322310D03*
X781290Y1328490D03*
X790290Y1328410D03*
X785640Y1328370D03*
X863900Y463100D03*
X848325Y480275D03*
X866100Y479900D03*
X856900Y479950D03*
X873000Y479900D03*
X864100Y492800D03*
X854600Y493000D03*
X891800Y1349965D03*
X888856Y1537644D03*
X941841Y1258580D03*
X903539Y1305368D03*
X920552Y1284112D03*
X963780Y1022400D03*
X966081Y1230097D03*
X954700Y1524100D03*
Y1530363D03*
X974787Y1525100D03*
Y1529300D03*
X1040180Y437510D03*
X1028657Y1009103D03*
X1026100Y1363300D03*
X1023700Y1359525D03*
X1022232Y1414851D03*
X1035600Y1520600D03*
X1079455Y-30742D03*
X1043674Y451921D03*
X1073408Y942399D03*
X1058571Y943852D03*
X1055881Y1006428D03*
X1065475Y1013261D03*
X1047700Y1481500D03*
X1124024Y-30840D03*
X1128765Y-34297D03*
X1111254Y-31020D03*
X1105328Y-31005D03*
X1146768Y-31238D03*
X1139808Y-31171D03*
X1149699Y-35153D03*
X1142293Y-37522D03*
X1215795Y181242D03*
X1324207Y138756D03*
X1315102Y137903D03*
X1316000Y772200D03*
X1312767Y885535D03*
X1375700Y413400D03*
X1347600Y734078D03*
X1344062Y737800D03*
X1354500Y747304D03*
X1360920Y749829D03*
X1334300Y771200D03*
X1338729Y776131D03*
X1338700Y771500D03*
X1373519Y761900D03*
X1369600Y1330100D03*
X1373700Y1330000D03*
X1414882Y397271D03*
X1418225Y421700D03*
X1421239Y558029D03*
Y562229D03*
X1442500Y548400D03*
Y554700D03*
X1474083Y764750D03*
X1471608Y768500D03*
X1500539Y739639D03*
X1498000Y743000D03*
X1489000Y723000D03*
X1476558Y759088D03*
X1479033Y762259D03*
X1486600Y786559D03*
X1494662Y1336000D03*
X1548021Y544100D03*
X1554813Y548500D03*
X1713879Y1005156D03*
X1719681Y1015301D03*
X1799100Y1018400D03*
X1783963Y1018325D03*
X1775863Y1015225D03*
X1843200Y912813D03*
X1825821Y907899D03*
X1841065D03*
X1860570Y936809D03*
X1842000Y1344700D03*
X1867763Y805386D03*
X1896801Y875796D03*
X1901442Y884012D03*
X1906010Y880553D03*
X1892673Y913996D03*
X1901442Y901000D03*
X1891098Y933500D03*
X1891616Y925702D03*
X1886814Y929000D03*
X1897507Y905750D03*
X1872024Y932518D03*
X1892473Y942674D03*
X1911676Y900821D03*
G54D14*
X35506Y-110687D03*
X63128Y89671D03*
X60754Y1316385D03*
X72380Y1596505D03*
X1861177Y91072D03*
X1874818Y-110232D03*
G54D42*
X151256Y1002801D03*
X217956Y590801D03*
X745861Y868854D03*
X722625Y873544D03*
X1793056Y1014801D03*
X1847200Y907500D03*
G54D51*
X749383Y864989D03*
X717454Y876958D03*
X741682Y904102D03*
X863000Y458600D03*
X971200Y1516700D03*
Y1520700D03*
X1900200Y933500D03*
Y929000D03*
G54D60*
X733582Y862826D03*
X718552Y887720D03*
X746183Y905889D03*
X756717Y876889D03*
X751711Y876917D03*
X1876271Y936966D03*
X1888000Y895200D03*
G54D24*
X96393Y981195D03*
X163093Y569195D03*
X751983Y920289D03*
X1736511Y1002024D03*
X1835866Y907899D03*
X1861800Y965000D03*
X1887520Y874918D03*
G54D33*
G01X73937Y654417D02*
X68800Y649280D01*
Y509900D01*
X67500Y508600D01*
G01X63463Y981325D02*
X58175D01*
G01X63500Y975500D02*
X63463Y975537D01*
Y981325D01*
G01Y987325D02*
X70610Y994472D01*
X79563D01*
G01X95437Y181161D02*
X102024Y174574D01*
Y168026D01*
X107586Y162464D01*
X197864D01*
X216761Y181361D01*
X219749D01*
G01X142687Y248100D02*
X95437Y200850D01*
Y181161D01*
G01X219749Y623417D02*
X102055D01*
X95437Y630035D01*
Y633917D01*
G01D02*
Y653517D01*
X142687Y700767D01*
G01X79563Y994472D02*
X90316D01*
X95363Y989425D01*
Y987725D01*
G01X219749Y1086873D02*
X217676Y1084800D01*
X162500D01*
X159700Y1082000D01*
X100210D01*
X95537Y1086673D01*
G01X142687Y1153523D02*
X95537Y1106373D01*
Y1086673D01*
G01X146263Y582472D02*
X157016D01*
X162063Y577425D01*
Y575725D01*
G01X129763Y560725D02*
Y569725D01*
X142510Y582472D01*
X146263D01*
G01X172911Y968100D02*
X159500D01*
X156941Y970659D01*
Y992644D01*
G01X151536Y993924D02*
Y974228D01*
X151563Y974201D01*
Y971225D01*
X148438Y968100D01*
X138289D01*
G01X218236Y581924D02*
Y562228D01*
X218263Y562201D01*
Y559225D01*
X215138Y556100D01*
X204989D01*
G01X219749Y181361D02*
X221339D01*
X229004Y173696D01*
Y167101D01*
X234061Y162044D01*
X309876D01*
X328993Y181161D01*
X343962D01*
G01X266899Y248011D02*
X249700Y230812D01*
Y221600D01*
X219749Y191649D01*
Y181361D01*
G01X223641Y580644D02*
Y558659D01*
X226200Y556100D01*
X239611D01*
G01X219749Y623417D02*
X229417D01*
X235717Y629717D01*
X339662D01*
X343862Y633917D01*
G01X219749Y623417D02*
Y653617D01*
X266899Y700767D01*
G01X219749Y1086873D02*
X224149Y1082473D01*
X339762D01*
X344062Y1086773D01*
G01X271165Y1147172D02*
X260472D01*
X219749Y1106449D01*
Y1086873D01*
G01X303029Y68429D02*
X303079Y68379D01*
X312079D01*
G01X313628Y112926D02*
X308500Y107798D01*
Y73900D01*
X303029Y68429D01*
G01X312079Y68379D02*
X322466D01*
X322500Y68345D01*
G01X314370Y118452D02*
Y113668D01*
X313628Y112926D01*
G01X323813Y118512D02*
X323753Y118452D01*
X314370D01*
G01X363248Y-425196D02*
Y-505196D01*
G01D02*
X1639148D01*
G01X359248Y-409196D02*
G02I-12000J0D01*
G01X354098D02*
G02I-6850J0D01*
G01X347248Y-425196D02*
Y-393196D01*
G01X363248Y-425196D02*
X1639148D01*
G01X363248Y-460696D02*
X1639148D01*
G01X363248Y-409196D02*
X331248D01*
G01X322500Y68345D02*
X325245D01*
X334845Y58745D01*
G01X343962Y181161D02*
X337721Y174920D01*
Y129821D01*
G01D02*
X326412Y118512D01*
X323813D01*
G01X390412Y248011D02*
X374700Y232299D01*
Y222200D01*
X343962Y191462D01*
Y181161D01*
G01X468174Y633917D02*
X450297D01*
X430046Y613666D01*
X359204D01*
X350110Y622760D01*
Y627669D01*
X343862Y633917D01*
G01X391112Y700767D02*
X348222Y657877D01*
Y638277D01*
X343862Y633917D01*
G01X447173Y1068726D02*
X434499Y1081400D01*
X349435D01*
X344062Y1086773D01*
G01X391112Y1153500D02*
X344062Y1106450D01*
Y1086773D01*
G01X447173Y1068726D02*
X448999Y1066900D01*
X551200D01*
X571173Y1086873D01*
X592387D01*
G01X506700Y1145973D02*
X503973D01*
X447173Y1089173D01*
Y1068726D01*
G01X468174Y633917D02*
Y624826D01*
X480297Y612703D01*
X493871D01*
X510072Y628904D01*
X587274D01*
X592387Y634017D01*
G01X468174Y633917D02*
X468074Y634017D01*
Y653417D01*
X515324Y700667D01*
G01X592387Y634017D02*
Y653517D01*
X639537Y700667D01*
Y700767D01*
G01X716600Y633917D02*
X680900D01*
X673022Y626039D01*
X605561D01*
X597583Y634017D01*
X592387D01*
G01X688563Y961355D02*
X569350D01*
G01X716600Y1086673D02*
X645969D01*
X641696Y1082400D01*
X605273D01*
X600800Y1086873D01*
X592387D01*
G01X639537Y1153523D02*
X592387Y1106373D01*
Y1086873D01*
G01X693563Y961355D02*
X688563D01*
G01X720748Y-425196D02*
Y-505196D01*
G01X716600Y633917D02*
X725171D01*
X818843Y540245D01*
X826355D01*
X876250Y490350D01*
Y481650D01*
X878500Y479400D01*
Y476000D01*
G01X755000Y677700D02*
X749428D01*
X716600Y644872D01*
Y633917D01*
G01X714004Y876958D02*
X708683D01*
G01X751711Y876717D02*
X747656D01*
G01X733582Y862626D02*
Y857988D01*
X733422Y857828D01*
G01X731383Y910189D02*
X732883Y911689D01*
X740383D01*
G01X746183D02*
X740383D01*
G01X745933Y915989D02*
Y911939D01*
X746183Y911689D01*
G01X711383Y909689D02*
X709133Y911939D01*
X703883D01*
G01X736462Y948996D02*
Y966362D01*
X742200Y972100D01*
Y1066499D01*
X722026Y1086673D01*
X716600D01*
G01X877673Y868873D02*
X845727D01*
X762750Y951850D01*
X739316D01*
X736462Y948996D01*
G01X756250Y1151750D02*
Y1146123D01*
X716600Y1106473D01*
Y1086673D01*
G01X878673Y804527D02*
X795274D01*
X755000Y764253D01*
Y677700D01*
G01X846400Y469300D02*
X849650D01*
X850100Y469750D01*
G01Y473250D02*
X849450Y473900D01*
X846400D01*
G01X858248Y-425196D02*
Y-505196D01*
G01X881750Y37397D02*
Y-65936D01*
X916644Y-100830D01*
X999220D01*
X1004213Y-95837D01*
G01X855450Y458500D02*
Y456150D01*
X857300Y454300D01*
G01X859550Y458600D02*
Y456550D01*
X857300Y454300D01*
G01X874800Y463950D02*
X871848D01*
X871487Y463589D01*
G01X874800Y467450D02*
Y471450D01*
X874900Y471550D01*
G01X878500Y476000D02*
Y473700D01*
X876350Y471550D01*
X874900D01*
G01X936994Y1379895D02*
X941507Y1375382D01*
X988453D01*
X1017771Y1404700D01*
X1028000D01*
G01X973248Y-425196D02*
Y-505196D01*
G01X1004213Y-95837D02*
Y-80913D01*
X1000300Y-77000D01*
Y-74200D01*
G01D02*
X1004300Y-70200D01*
Y-48500D01*
X1007582Y-45218D01*
Y-39418D01*
G01X1007372Y1023832D02*
Y1024018D01*
X1017194Y1033840D01*
G01X1025335Y1324216D02*
Y1330916D01*
G01D02*
Y1337616D01*
G01D02*
X1025286D01*
Y1341216D01*
X1025284D01*
G01X1069000Y1067100D02*
X1072500Y1070600D01*
Y1104900D01*
X1068700Y1108700D01*
G01X1128900Y1067200D02*
X1145900D01*
X1164200Y1067700D01*
X1194000Y1037900D01*
G01X1271648Y-425196D02*
Y-505196D01*
G01X1373553Y700994D02*
X1267302D01*
X1265891Y699583D01*
G01D02*
Y710276D01*
X1263250Y712917D01*
Y823436D01*
G01X1268948Y1150173D02*
X1295100Y1124021D01*
Y1082673D01*
X1309600Y1068173D01*
G01X1312000Y615417D02*
X1423262D01*
X1425962Y618117D01*
X1433513D01*
X1436213Y615417D01*
G01X1309600Y1068173D02*
X1328127Y1086700D01*
X1352700D01*
X1373000Y1066400D01*
X1420345D01*
X1424760Y1061985D01*
X1430025D01*
X1436213Y1068173D01*
G01X1414319Y523900D02*
X1408362Y529857D01*
X1390400D01*
X1387743Y527200D01*
X1364257D01*
X1361600Y529857D01*
X1346057D01*
G01X1370716Y1148037D02*
X1372852Y1150173D01*
X1382500D01*
X1422194Y1110479D01*
Y1082192D01*
X1436213Y1068173D01*
G01X1500600Y523300D02*
X1491700D01*
X1487800Y519400D01*
X1445900D01*
X1425200Y540100D01*
G01X1414319Y523900D02*
X1414600Y524181D01*
Y532800D01*
X1421900Y540100D01*
X1425200D01*
G01X1441648Y-425196D02*
Y-505196D01*
G01X1436213Y615417D02*
X1544928D01*
X1549248Y611097D01*
X1556105D01*
X1560425Y615417D01*
G01X1436213Y1068173D02*
X1544796D01*
X1550305Y1062664D01*
X1554916D01*
X1560425Y1068173D01*
G01Y615417D02*
X1548222Y627620D01*
Y653478D01*
X1497142Y704558D01*
X1495480D01*
G01X1495900Y1149000D02*
X1503803D01*
X1542400Y1110403D01*
Y1086198D01*
X1560425Y1068173D01*
G01Y162661D02*
X1673576D01*
X1676276Y165361D01*
X1681938D01*
X1684638Y162661D01*
G01X1560425Y615417D02*
X1667338D01*
X1670038Y612717D01*
X1681938D01*
X1684638Y615417D01*
G01Y1068173D02*
X1679129Y1062664D01*
X1672224D01*
X1666715Y1068173D01*
X1560425D01*
G01X1684638Y615417D02*
X1669300Y630755D01*
Y648686D01*
X1620469Y697517D01*
G01X1639148Y-425196D02*
Y-505196D01*
G01X1667148Y-409196D02*
G02I-12000J0D01*
G01X1661998D02*
G02I-6850J0D01*
G01X1655148Y-425196D02*
Y-393196D01*
G01X1671148Y-409196D02*
X1639148D01*
G01X1684638Y162661D02*
Y166862D01*
X1666800Y184700D01*
Y213900D01*
X1636039Y244661D01*
X1621100D01*
G01X1684638Y1068173D02*
X1670400Y1082411D01*
Y1119061D01*
X1635688Y1153773D01*
G01X1808850Y162661D02*
X1806150Y165361D01*
X1793361D01*
X1790661Y162661D01*
X1684638D01*
G01X1808850Y615417D02*
Y601715D01*
X1784429Y577294D01*
X1722761D01*
X1684638Y615417D01*
G01X1719681Y1015301D02*
X1708215D01*
X1702761Y1009847D01*
G01X1684638Y1068173D02*
X1793125D01*
X1795825Y1070873D01*
X1802350D01*
X1805250Y1067973D01*
G01X1735481Y1008554D02*
Y1010481D01*
X1730661Y1015301D01*
X1719681D01*
G01X1845517Y158475D02*
X1845417Y158575D01*
X1845225D01*
X1841139Y162661D01*
X1808850D01*
G01Y615417D02*
X1821804D01*
X1825890Y611331D01*
X1845317D01*
X1845417Y611231D01*
G01X1798741Y1004644D02*
Y982659D01*
X1801300Y980100D01*
X1814711D01*
G01X1793336Y1005924D02*
Y986228D01*
X1793363Y986201D01*
Y983225D01*
X1790238Y980100D01*
X1780089D01*
G01X1805250Y1067973D02*
X1811883Y1061340D01*
Y1051084D01*
X1826239Y1036728D01*
X1849998D01*
X1862478Y1049208D01*
X1870444D01*
X1876662Y1055426D01*
G01X1876938Y181062D02*
Y174638D01*
X1860775Y158475D01*
X1845517D01*
G01X1878900Y637000D02*
X1868500Y626600D01*
X1860786D01*
X1845417Y611231D01*
G01X1881720Y874918D02*
X1859735D01*
X1857176Y872359D01*
Y858948D01*
G01X1883000Y880323D02*
X1863304D01*
X1863277Y880296D01*
X1860301D01*
X1857176Y883421D01*
Y893570D01*
G01X1843200Y918500D02*
Y912813D01*
G01D02*
Y911550D01*
X1847250Y907500D01*
G01X1830066Y907899D02*
X1825821D01*
G01D02*
X1821152D01*
G01X1847250Y904000D02*
X1844964D01*
X1841065Y907899D01*
G01D02*
X1836066D01*
G01X1862000Y965000D02*
X1881795D01*
X1892473Y954322D01*
Y942674D01*
G01X1878900Y637000D02*
X1880810Y635090D01*
X1882400D01*
X1886028Y631462D01*
Y591955D01*
X1912869Y565114D01*
Y186373D01*
X1904288Y177792D01*
X1887451D01*
X1883501Y181742D01*
X1877618D01*
X1876938Y181062D01*
G01X1878900Y637000D02*
X1881400Y639500D01*
X1891025D01*
X1899977Y630548D01*
X1904288D01*
X1920921Y647181D01*
Y938885D01*
X1878796Y981010D01*
Y1030196D01*
X1890102Y1041502D01*
Y1057921D01*
X1888085Y1059938D01*
G01X1892443Y897500D02*
Y894350D01*
G01X1892500Y890750D02*
Y894293D01*
X1892443Y894350D01*
G01X1888000Y895000D02*
X1884200D01*
G01X1896943Y897500D02*
Y894350D01*
G01X1884500Y909250D02*
Y912500D01*
G01X1900250Y933500D02*
X1904000D01*
G01X1900250Y929000D02*
X1904000D01*
G01X1900250Y925000D02*
X1904000D01*
G01X1906500Y890250D02*
Y893400D01*
G01X1888000Y890750D02*
X1884800D01*
G01X1892473Y942674D02*
Y940552D01*
X1889917Y937996D01*
X1882801D01*
G01X1888085Y1059938D02*
X1881174D01*
X1876662Y1055426D01*
X127988Y190242D03*
Y185742D03*
Y194242D03*
Y181742D03*
Y634498D03*
Y638498D03*
Y642998D03*
Y646998D03*
Y1087254D03*
Y1091254D03*
Y1095754D03*
Y1099754D03*
X252200Y190242D03*
Y185742D03*
Y194242D03*
Y181742D03*
Y634498D03*
Y638498D03*
Y642998D03*
Y646998D03*
Y1087254D03*
Y1091254D03*
Y1095754D03*
Y1099754D03*
X376413Y190242D03*
Y185742D03*
Y194242D03*
Y181742D03*
Y634498D03*
Y638498D03*
Y642998D03*
Y646998D03*
Y1087254D03*
Y1091254D03*
Y1095754D03*
Y1099754D03*
X500625Y190242D03*
Y185742D03*
Y194242D03*
Y181742D03*
Y634498D03*
Y638498D03*
Y642998D03*
Y646998D03*
Y1087254D03*
Y1091254D03*
Y1095754D03*
Y1099754D03*
X624838Y190242D03*
Y185742D03*
Y194242D03*
Y181742D03*
Y634498D03*
Y638498D03*
Y642998D03*
Y646998D03*
Y1087254D03*
Y1091254D03*
Y1095754D03*
Y1099754D03*
X749051Y190242D03*
Y185742D03*
Y194242D03*
Y181742D03*
Y634498D03*
Y638498D03*
Y642998D03*
Y646998D03*
Y1087254D03*
Y1091254D03*
Y1095754D03*
Y1099754D03*
X1066750Y1224035D03*
X1070750D03*
X1075250D03*
X1079250D03*
X1066750Y1209862D03*
X1070750D03*
X1075250D03*
X1079250D03*
X1066750Y1216949D03*
X1070750D03*
X1075250D03*
X1079250D03*
X1066750Y1231122D03*
X1070750D03*
X1075250D03*
X1079250D03*
X1066750Y1238209D03*
X1070750D03*
X1075250D03*
X1079250D03*
X1066750Y1245295D03*
X1070750D03*
X1075250D03*
X1079250D03*
X1066750Y1301988D03*
X1070750D03*
X1075250D03*
X1079250D03*
X1066750Y1309075D03*
X1070750D03*
X1075250D03*
X1079250D03*
X1066750Y1316161D03*
X1070750D03*
X1075250D03*
X1079250D03*
X1066750Y1323248D03*
X1070750D03*
X1075250D03*
X1079250D03*
X1066750Y1294902D03*
X1070750D03*
X1075250D03*
X1079250D03*
X1066750Y1330335D03*
X1070750D03*
X1075250D03*
X1079250D03*
X1066750Y1387028D03*
X1070750D03*
X1075250D03*
X1079250D03*
X1066750Y1394114D03*
X1070750D03*
X1075250D03*
X1079250D03*
X1066750Y1401201D03*
X1070750D03*
X1075250D03*
X1079250D03*
X1066750Y1408287D03*
X1070750D03*
X1075250D03*
X1079250D03*
X1066750Y1415374D03*
X1070750D03*
X1075250D03*
X1079250D03*
X1066750Y1379941D03*
X1070750D03*
X1075250D03*
X1079250D03*
X1278900Y182823D03*
X1274900D03*
X1270400D03*
X1266400D03*
X1261250Y167823D03*
X1256750D03*
X1265250D03*
X1252750D03*
X1278500Y634498D03*
Y638498D03*
Y642998D03*
Y646998D03*
X1259800Y631998D03*
Y627998D03*
Y623498D03*
Y619498D03*
Y1080754D03*
Y1076254D03*
Y1072254D03*
X1278500Y1087254D03*
Y1091254D03*
Y1095754D03*
Y1099754D03*
X1259800Y1084754D03*
X1376963Y167823D03*
X1402713Y181742D03*
Y185742D03*
Y190242D03*
Y194242D03*
X1380963Y167823D03*
X1385463D03*
X1389463D03*
X1402713Y634498D03*
Y638498D03*
Y642998D03*
Y646998D03*
X1384013Y631998D03*
Y627998D03*
Y623498D03*
Y619498D03*
Y1080754D03*
Y1076254D03*
Y1072254D03*
X1402713Y1087254D03*
Y1091254D03*
Y1095754D03*
Y1099754D03*
X1384013Y1084754D03*
X1515450Y181700D03*
X1511450D03*
X1506950D03*
X1502950D03*
X1508225Y631998D03*
Y627998D03*
Y623498D03*
Y619498D03*
Y1080754D03*
Y1076254D03*
Y1072254D03*
Y1084754D03*
X1526925Y181742D03*
Y185742D03*
Y190242D03*
Y194242D03*
Y634498D03*
Y638498D03*
Y642998D03*
Y646998D03*
Y1087254D03*
Y1091254D03*
Y1095754D03*
Y1099754D03*
X1651138Y181742D03*
Y185742D03*
Y190242D03*
Y194242D03*
X1632438Y179242D03*
Y175242D03*
Y170742D03*
Y166742D03*
X1651138Y634498D03*
Y638498D03*
Y642998D03*
Y646998D03*
X1632438Y631998D03*
Y627998D03*
Y623498D03*
Y619498D03*
Y1080754D03*
Y1076254D03*
Y1072254D03*
X1651138Y1087254D03*
Y1091254D03*
Y1095754D03*
Y1099754D03*
X1632438Y1084754D03*
X1756650Y179242D03*
Y175242D03*
Y170742D03*
Y166742D03*
X1725350Y634498D03*
Y638498D03*
Y642998D03*
Y646998D03*
X1731650Y631998D03*
Y627998D03*
Y623498D03*
Y619498D03*
X1756650Y1080754D03*
Y1076254D03*
Y1072254D03*
Y1084754D03*
X1775350Y181742D03*
Y185742D03*
Y190242D03*
Y194242D03*
Y1087254D03*
Y1091254D03*
Y1095754D03*
Y1099754D03*
X1899563Y181742D03*
Y185742D03*
Y190242D03*
Y194242D03*
X1880863Y179242D03*
Y175242D03*
Y170742D03*
Y166742D03*
X1899563Y634498D03*
Y638498D03*
Y642998D03*
Y646998D03*
X1880863Y631998D03*
Y627998D03*
Y623498D03*
Y619498D03*
Y1080754D03*
Y1076254D03*
Y1072254D03*
X1899563Y1087254D03*
Y1091254D03*
Y1095754D03*
Y1099754D03*
X1880863Y1084754D03*
G54D15*
G01X99700Y991400D02*
Y988488D01*
X103082Y985106D01*
X106157D01*
G01X101403Y981195D02*
X101429Y981169D01*
X106157D01*
G01X96593Y981195D02*
X101403D01*
G01X108063Y991925D02*
X106157Y990019D01*
Y989043D01*
G01X104230Y992209D02*
X102863Y990842D01*
Y987972D01*
X103761Y987074D01*
X106157D01*
G01X119741Y995666D02*
X121966D01*
X124000Y997700D01*
X125550D01*
G01X166400Y579400D02*
Y576488D01*
X169782Y573106D01*
X172857D01*
G01X168103Y569195D02*
X168129Y569169D01*
X172857D01*
G01X163293Y569195D02*
X168103D01*
G01X137063Y993725D02*
X129563Y986225D01*
X129163D01*
X128044Y985106D01*
X125443D01*
G01X137163Y987125D02*
Y986425D01*
X131907Y981169D01*
X125443D01*
G01X145363Y997741D02*
X140826D01*
G01X131110Y993257D02*
X131163Y993204D01*
Y990425D01*
X127812Y987074D01*
X125443D01*
G01X151306Y1002801D02*
X147482Y1006625D01*
X142563D01*
G01X125550Y997700D02*
Y994000D01*
X125443Y993893D01*
Y989043D01*
G01X125550Y997700D02*
Y1001488D01*
X125313Y1001725D01*
G01D02*
Y1002475D01*
X129463Y1006625D01*
X142563D01*
G01X128813Y1001725D02*
X130313Y1003225D01*
X134063D01*
G01X134826Y997741D02*
Y1002462D01*
X134063Y1003225D01*
G01X129050Y997700D02*
X134785D01*
X134826Y997741D01*
G01X203763Y581725D02*
X196263Y574225D01*
X195863D01*
X194744Y573106D01*
X192143D01*
G01X212063Y585741D02*
X207526D01*
G01X197810Y581257D02*
X197863Y581204D01*
Y578425D01*
X194512Y575074D01*
X192143D01*
G01X174763Y579925D02*
X172857Y578019D01*
Y577043D01*
G01X203863Y575125D02*
Y574425D01*
X198607Y569169D01*
X192143D01*
G01X170930Y580209D02*
X169563Y578842D01*
Y575972D01*
X170461Y575074D01*
X172857D01*
G01X218006Y590801D02*
X214382Y594425D01*
X209163D01*
G01X192050Y585700D02*
Y582000D01*
X192143Y581907D01*
Y577043D01*
G01X192050Y585700D02*
X192013Y585737D01*
Y589725D01*
G01X186441Y583666D02*
X188566D01*
X190600Y585700D01*
X192050D01*
G01X192013Y589725D02*
Y590475D01*
X195963Y594425D01*
X209163D01*
G01X195513Y589725D02*
X197013Y591225D01*
X200763D01*
G01X201526Y585741D02*
Y590462D01*
X200763Y591225D01*
G01X195550Y585700D02*
X201485D01*
X201526Y585741D01*
G01X227063Y991975D02*
Y989725D01*
G01Y992475D02*
Y994925D01*
G01X293763Y579975D02*
Y577725D01*
G01Y580475D02*
Y582925D01*
G01X530130Y547167D02*
X495235Y582062D01*
X472022D01*
G01X515800Y1028000D02*
Y1001994D01*
X636344Y881450D01*
X706084D01*
G01X627000Y538581D02*
X625736Y539845D01*
X623268D01*
X612921Y529498D01*
X601278D01*
X590813Y539963D01*
X587711D01*
X585479Y537731D01*
G01X627000Y542909D02*
X625736Y541645D01*
X622522D01*
X612175Y531298D01*
X602024D01*
X591559Y541763D01*
X587710D01*
X585479Y543994D01*
G01X683341Y580479D02*
X685644Y578176D01*
Y575003D01*
X667558Y556917D01*
X614648D01*
X604479Y546748D01*
Y541415D01*
X605988Y539906D01*
X607734D01*
X609334Y538306D01*
G01X579529Y562951D02*
X571529D01*
G01X689747Y580479D02*
X687444Y578176D01*
Y574257D01*
X668304Y555117D01*
X615394D01*
X606279Y546002D01*
Y542161D01*
X606734Y541706D01*
X607734D01*
X609334Y543306D01*
G01X706084Y881450D02*
X711711D01*
G01X737984Y861689D02*
Y865346D01*
G01X743200Y874550D02*
X744950D01*
X746800Y872700D01*
G01X749411Y868854D02*
Y870089D01*
X746800Y872700D01*
G01X754104Y864973D02*
X749449D01*
X749433Y864989D01*
G01D02*
X749411Y865011D01*
Y868854D01*
G01X711711Y884950D02*
Y889411D01*
X712489Y890189D01*
X713883D01*
G01X724826Y887518D02*
X724824Y887520D01*
X718552D01*
G01D02*
X715883Y890189D01*
X713883D01*
G01X726175Y873544D02*
Y875481D01*
X727883Y877189D01*
G01X729898Y882446D02*
Y879204D01*
X727883Y877189D01*
G01X736938Y887518D02*
X741682D01*
X743000Y886200D01*
G01X751711Y882717D02*
X746483D01*
X743000Y886200D01*
G01X733835Y882396D02*
Y880837D01*
X737687Y876985D01*
Y872489D01*
G01X741883Y868839D02*
X741876Y868846D01*
X737984D01*
G01X745911Y868854D02*
X745896Y868839D01*
X741883D01*
G01X745933Y864989D02*
Y868832D01*
X745911Y868854D01*
G01X737984Y868846D02*
X737687Y869143D01*
Y872489D01*
G01X741883Y865339D02*
Y861389D01*
G01X743200Y878050D02*
Y881658D01*
G01X736988Y885549D02*
X739309D01*
X743200Y881658D01*
G01X731866Y882446D02*
Y873789D01*
G01X733582Y868626D02*
Y871082D01*
X731866Y872798D01*
Y873789D01*
G01X729182Y865952D02*
X731856Y868626D01*
X733582D01*
G01X729182Y862452D02*
Y858888D01*
X726258Y855964D01*
X722108D01*
X719119Y858953D01*
G01D02*
X713357Y864715D01*
Y871360D01*
X717504Y875507D01*
Y876958D01*
G01D02*
Y880704D01*
X722349Y885549D01*
X724776D01*
G01X744133Y924689D02*
X741883D01*
G01X744633D02*
X747383D01*
G01X752183Y920289D02*
Y918739D01*
X749433Y915989D01*
G01D02*
Y914594D01*
X751397Y912630D01*
X753893D01*
G01X760104Y864973D02*
Y867974D01*
X759104Y868974D01*
X757664D01*
G01X756717Y882689D02*
X756689Y882717D01*
X751711D01*
G01X890552Y1626378D02*
X888978D01*
X885700Y1623100D01*
Y1540800D01*
X888856Y1537644D01*
G01D02*
X900000Y1526500D01*
G01X940750Y1549200D02*
X948750D01*
G01X967750Y1516700D02*
X966650Y1517800D01*
X963908D01*
X963058Y1516950D01*
X961000D01*
G01D02*
X958942D01*
X958092Y1517800D01*
X951500D01*
X948200Y1521100D01*
Y1524905D01*
G02X951427Y1528132I3227J0D01*
G01X953609D01*
G03X954083Y1528241I0J1084D01*
G03X954700Y1529227I-479J986D01*
G01Y1530363D01*
G01X974787Y1529300D02*
X975280Y1528806D01*
G03X977010Y1528090I1729J1730D01*
G01X978010D01*
G02X981540Y1524560I0J-3530D01*
G01Y1520680D01*
X978650Y1517790D01*
X973710D01*
X972620Y1516700D01*
X971250D01*
G01X967750Y1520700D02*
X966650Y1519600D01*
X963908D01*
X963058Y1520450D01*
X961000D01*
G01D02*
X958942D01*
X958092Y1519600D01*
X952246D01*
X950000Y1521846D01*
Y1524905D01*
G02X951427Y1526332I1427J0D01*
G01X953604D01*
G02X954700Y1525236I0J-1096D01*
G01Y1524100D01*
G01X971250Y1520700D02*
X972630D01*
X973740Y1519590D01*
X977904D01*
X979740Y1521426D01*
Y1524560D01*
G03X978010Y1526290I-1730J0D01*
G01X977010D01*
G03X975246Y1525560I-1J-2494D01*
G01X974787Y1525100D01*
G01X1357316Y542311D02*
X1357530Y542097D01*
X1410297D01*
X1415200Y547000D01*
X1430300D01*
X1432300Y545000D01*
X1446200D01*
X1455750Y554550D01*
Y572350D01*
G01X1425950Y558100D02*
X1424921Y559129D01*
X1422339D01*
X1421239Y558029D01*
G01D02*
X1420039Y559229D01*
X1415195D01*
X1411300Y563124D01*
Y569500D01*
X1405300Y575500D01*
X1398400D01*
X1396297Y573397D01*
G01X1425950Y562100D02*
X1424779Y560929D01*
X1422539D01*
X1421239Y562229D01*
G01D02*
X1420039Y561029D01*
X1415941D01*
X1413100Y563870D01*
Y570246D01*
X1406046Y577300D01*
X1398800D01*
X1396297Y579803D01*
G01X1436200Y561850D02*
X1437150Y560900D01*
X1445570D01*
X1448900Y557570D01*
Y553400D01*
X1445868Y550368D01*
X1443400D01*
X1442500Y549468D01*
Y548400D01*
G01X1448450Y529600D02*
X1456450D01*
G01X1436200Y558350D02*
X1436950Y559100D01*
X1444824D01*
X1447100Y556824D01*
Y554146D01*
X1445122Y552168D01*
X1442900D01*
X1442500Y552568D01*
Y554700D01*
G01X1429450Y558100D02*
X1430650Y559300D01*
X1435250D01*
X1436200Y558350D01*
G01X1429450Y562100D02*
X1430450Y561100D01*
X1435450D01*
X1436200Y561850D01*
G01X1497849Y545264D02*
Y545349D01*
X1501000Y548500D01*
X1554813D01*
G01X1568000D02*
X1554813D01*
G01X1740499Y1008223D02*
X1742243Y1006479D01*
Y999745D01*
X1744882Y997106D01*
X1747957D01*
G01X1749863Y1003925D02*
X1747957Y1002019D01*
Y1001043D01*
G01X1746030Y1004209D02*
X1744663Y1002842D01*
Y999972D01*
X1745561Y999074D01*
X1747957D01*
G01X1761541Y1007666D02*
X1763866D01*
X1765900Y1009700D01*
X1767350D01*
G01X1737241Y997843D02*
X1736711Y998373D01*
Y1002024D01*
G01X1737241Y997843D02*
Y997160D01*
X1741232Y993169D01*
X1747957D01*
G01X1778863Y1005725D02*
X1771363Y998225D01*
X1770963D01*
X1769844Y997106D01*
X1767243D01*
G01X1787163Y1009741D02*
X1782626D01*
G01X1772863Y1005304D02*
Y1002325D01*
X1769612Y999074D01*
X1767243D01*
G01X1778963Y999125D02*
X1773007Y993169D01*
X1767243D01*
G01X1793106Y1014801D02*
X1789582Y1018325D01*
X1783963D01*
G01X1767350Y1009700D02*
Y1003264D01*
X1767243Y1003157D01*
Y1001043D01*
G01X1767350Y1009700D02*
Y1013488D01*
X1767113Y1013725D01*
G01D02*
Y1014475D01*
X1770963Y1018325D01*
X1783963D01*
G01X1770613Y1013725D02*
X1772113Y1015225D01*
X1775863D01*
G01X1776626Y1009741D02*
Y1014462D01*
X1775863Y1015225D01*
G01X1770850Y1009700D02*
X1772100D01*
X1772141Y1009741D01*
X1776626D01*
G01X1858626Y800787D02*
X1862144D01*
G01X1858126D02*
X1855676D01*
G01X1874182Y906416D02*
Y903815D01*
X1875301Y902696D01*
X1875379D01*
X1876825Y901250D01*
X1877814D01*
X1881500Y897564D01*
Y889500D01*
X1883750Y887250D01*
X1888000D01*
G01X1892500D02*
X1896750D01*
X1898000Y888500D01*
G01X1888000Y887250D02*
X1892500D01*
G01X1898000Y888500D02*
X1902441D01*
G01X1901442Y884012D02*
X1903762D01*
X1906500Y886750D01*
G01X1901442Y884012D02*
X1881988D01*
X1879500Y886500D01*
Y896500D01*
X1877151Y898849D01*
X1871348D01*
X1870245Y899952D01*
Y906416D01*
G01X1891877Y880553D02*
X1906010D01*
G01D02*
X1908883D01*
X1915223Y886893D01*
Y908357D01*
X1911972Y911608D01*
X1901184D01*
X1898826Y909250D01*
X1893500D01*
G01X1905943Y897500D02*
X1909358D01*
G01X1900250Y938000D02*
X1904000D01*
G01X1911676Y900821D02*
Y904478D01*
X1910404Y905750D01*
X1907959D01*
G01X1888000Y901000D02*
X1885000D01*
X1883250Y902750D01*
X1877447D01*
X1876150Y904047D01*
Y906416D01*
G01X1892443Y901000D02*
X1896943D01*
G01X1888000D02*
X1892443D01*
G01X1901442D02*
X1896943D01*
G01X1905943D02*
X1901442D01*
G01X1896750Y938000D02*
Y933500D01*
G01D02*
X1891098D01*
G01D02*
X1883500D01*
X1880946Y930946D01*
X1876351D01*
X1874182Y928777D01*
Y925702D01*
G01X1896750Y921000D02*
Y925000D01*
G01X1878119Y925702D02*
X1891616D01*
G01D02*
X1894018D01*
X1894720Y925000D01*
X1896750D01*
G01X1876150Y925702D02*
Y928098D01*
X1877052Y929000D01*
X1886814D01*
G01D02*
X1896750D01*
G01X1889500Y909250D02*
X1893500D01*
G01X1884500Y905750D02*
X1881500D01*
X1880834Y906416D01*
X1878119D01*
G01X1884500Y905750D02*
X1885250D01*
X1888750Y909250D01*
X1889500D01*
G01X1893500Y905750D02*
X1889500D01*
G01X1897507D02*
X1893500D01*
G01X1901959D02*
X1897507D01*
G01X1900250Y921000D02*
X1904000D01*
G01X1876271Y936766D02*
X1872190D01*
G01X1872024Y932518D02*
X1873686Y934180D01*
Y934181D01*
X1876271Y936766D01*
G01X1870245Y925702D02*
Y930739D01*
X1872024Y932518D01*
G01X1867963Y993475D02*
Y991225D01*
G01Y993975D02*
Y996425D01*
G01X1911676Y893469D02*
Y900821D01*
X60540Y-85109D03*
X59536Y1573374D03*
X80019Y51968D03*
X111024Y153681D03*
Y302303D03*
Y606437D03*
Y755059D03*
Y1059193D03*
Y1207815D03*
X79000Y1301900D03*
X127263Y20472D03*
X173228Y1114173D03*
X235236Y153681D03*
Y302303D03*
Y606437D03*
Y755059D03*
Y1059193D03*
Y1207815D03*
X359449Y153681D03*
Y302303D03*
Y606437D03*
Y755059D03*
Y1059193D03*
Y1207815D03*
X496653Y80906D03*
Y110552D03*
X483661Y153681D03*
Y302303D03*
Y606437D03*
Y755059D03*
X503248Y829921D03*
X483661Y1059193D03*
Y1207815D03*
X607874Y302303D03*
Y755059D03*
Y1207815D03*
X631200Y51968D03*
X607874Y153681D03*
Y606437D03*
Y1059193D03*
X678444Y20472D03*
X670079Y1114173D03*
X732087Y153681D03*
Y302303D03*
Y606437D03*
Y755059D03*
Y1059193D03*
Y1207815D03*
X942126Y58465D03*
Y346457D03*
Y437598D03*
Y725590D03*
X949902Y-115157D03*
X1098524D03*
X1110236Y58465D03*
Y346457D03*
Y437598D03*
Y725590D03*
X1250689Y51969D03*
X1281693Y153681D03*
Y302303D03*
Y606437D03*
Y755059D03*
Y1059193D03*
Y1207815D03*
X1297933Y20472D03*
X1343700Y1114173D03*
X1405906Y153681D03*
Y302303D03*
Y606437D03*
Y755059D03*
Y1059193D03*
Y1207815D03*
X1465157Y80906D03*
Y110552D03*
X1530118Y153681D03*
Y302303D03*
Y606437D03*
Y755059D03*
Y1059193D03*
Y1207815D03*
X1654331Y153681D03*
Y302303D03*
Y606437D03*
Y755059D03*
X1673917Y829921D03*
X1654331Y1059193D03*
Y1207815D03*
X1801870Y51969D03*
X1778543Y153681D03*
Y302303D03*
Y606437D03*
Y755059D03*
Y1059193D03*
Y1207815D03*
X1849114Y20472D03*
X1826700Y77600D03*
X1840551Y1114173D03*
X1865705Y1573374D03*
X1898432Y-93682D03*
X1902756Y153681D03*
Y302303D03*
Y606437D03*
Y755059D03*
Y1059193D03*
Y1207815D03*
X1908500Y1346800D03*
G54D70*
X944881Y-58267D03*
G54D43*
X191400Y987400D03*
Y948300D03*
Y973100D03*
Y1012200D03*
X258100Y536300D03*
Y600200D03*
Y575400D03*
Y561100D03*
X1833200Y987700D03*
Y948600D03*
Y973400D03*
Y1012500D03*
G54D16*
X63500Y975500D03*
Y967900D03*
X71500Y967800D03*
Y975400D03*
X79300Y967800D03*
Y975400D03*
X87100Y967800D03*
Y975400D03*
X138200Y555800D03*
Y563400D03*
X146000Y555800D03*
Y563400D03*
X153800Y555800D03*
Y563400D03*
X205400Y989100D03*
Y996700D03*
X213200Y989100D03*
Y996700D03*
X221000Y989100D03*
Y996700D03*
X272100Y577100D03*
Y584700D03*
X279900Y577100D03*
Y584700D03*
X287700Y577100D03*
Y584700D03*
X701782Y929902D03*
Y922302D03*
X712898Y938082D03*
X720798D03*
X728698D03*
X712898Y945682D03*
X720798D03*
X728698D03*
X764418Y895398D03*
Y902998D03*
X756618Y895398D03*
Y902998D03*
X1703183Y996313D03*
Y988713D03*
X1711618Y988629D03*
Y996229D03*
X1719418Y988629D03*
Y996229D03*
X1727218Y988629D03*
Y996229D03*
X1847200Y990500D03*
Y998100D03*
X1855000Y990500D03*
Y998100D03*
X1862800Y990500D03*
Y998100D03*
X1882801Y937996D03*
Y945596D03*
G54D34*
X172911Y968100D03*
X138289D03*
X204989Y556100D03*
X239611D03*
X1814711Y980100D03*
X1780089D03*
G54D61*
X733582Y868426D03*
X746183Y911489D03*
X718552Y893320D03*
X756717Y882489D03*
X751711Y882517D03*
X1888000Y900800D03*
X1876271Y942566D03*
G54D25*
X90793Y981195D03*
X157493Y569195D03*
X746383Y920289D03*
X1730911Y1002024D03*
X1830266Y907899D03*
X1856200Y965000D03*
X1881920Y874918D03*
G54D52*
X730882Y888502D03*
G54D80*
G01X1070750Y1231122D02*
X1071712D01*
G02X1072425Y1230409I0J-713D01*
G01Y1229824D01*
G03X1075245Y1227004I2820J0D01*
G01X1099722D01*
G02X1101173Y1226403I0J-2052D01*
G02X1101265Y1226300I-882J-880D01*
G02X1101538Y1225522I-972J-778D01*
G01Y1224536D01*
G02X1101038Y1224036I-500J0D01*
G01X1099357D01*
G01X1070750Y1224035D02*
X1071712D01*
G02X1072425Y1223322I0J-713D01*
G01Y1222737D01*
G03X1075245Y1219917I2820J0D01*
G01X1095785D01*
G02X1097236Y1219316I0J-2052D01*
G02X1097328Y1219213I-882J-880D01*
G02X1097601Y1218435I-972J-778D01*
G01Y1217449D01*
G02X1097101Y1216949I-500J0D01*
G01X1095420D01*
G01X1100932D02*
X1099251D01*
G02X1098751Y1217449I0J500D01*
G01Y1218437D01*
G03X1098227Y1219932I-2395J0D01*
G03X1098050Y1220130I-1872J-1496D01*
G03X1095784Y1221067I-2264J-2266D01*
G01X1075245D01*
G02X1073575Y1222737I0J1670D01*
G01Y1223322D01*
G02X1074288Y1224035I713J0D01*
G01X1075250D01*
G01X1070750Y1216949D02*
X1071712D01*
G02X1072425Y1216236I0J-713D01*
G01Y1215651D01*
G03X1075245Y1212831I2820J0D01*
G01X1099722D01*
G02X1101173Y1212230I0J-2052D01*
G02X1101265Y1212127I-882J-880D01*
G02X1101538Y1211349I-972J-778D01*
G01Y1210363D01*
G02X1101038Y1209863I-500J0D01*
G01X1099357D01*
G01X1075250Y1216949D02*
X1074288D01*
G03X1073575Y1216236I0J-713D01*
G01Y1215651D01*
G03X1075245Y1213981I1670J0D01*
G01X1099721D01*
G02X1101987Y1213044I2J-3203D01*
G02X1102164Y1212846I-1695J-1694D01*
G02X1102688Y1211351I-1871J-1495D01*
G01Y1210363D01*
G03X1103188Y1209863I500J0D01*
G01X1104869D01*
G01X1070750Y1209862D02*
X1071712D01*
G02X1072425Y1209149I0J-713D01*
G01Y1208564D01*
G03X1075245Y1205744I2820J0D01*
G01X1095785D01*
G02X1097236Y1205143I0J-2052D01*
G02X1097328Y1205040I-882J-880D01*
G02X1097601Y1204262I-972J-778D01*
G01Y1203276D01*
G02X1097101Y1202776I-500J0D01*
G01X1095420D01*
G01X1100932D02*
X1099251D01*
G02X1098751Y1203276I0J500D01*
G01Y1204264D01*
G03X1098227Y1205759I-2395J0D01*
G03X1098050Y1205957I-1872J-1496D01*
G03X1095784Y1206894I-2264J-2266D01*
G01X1075245D01*
G02X1073575Y1208564I0J1670D01*
G01Y1209149D01*
G02X1074288Y1209862I713J0D01*
G01X1075250D01*
G01X1070750Y1245295D02*
X1071712D01*
G02X1072425Y1244582I0J-713D01*
G01Y1243997D01*
G03X1075245Y1241177I2820J0D01*
G01X1099722D01*
G02X1101173Y1240576I0J-2052D01*
G02X1101265Y1240473I-882J-880D01*
G02X1101538Y1239695I-972J-778D01*
G01Y1238709D01*
G02X1101038Y1238209I-500J0D01*
G01X1099357D01*
G01X1075250Y1245295D02*
X1074288D01*
G03X1073575Y1244582I0J-713D01*
G01Y1243997D01*
G03X1075245Y1242327I1670J0D01*
G01X1099721D01*
G02X1101987Y1241390I2J-3203D01*
G02X1102164Y1241192I-1695J-1694D01*
G02X1102688Y1239697I-1871J-1495D01*
G01Y1238709D01*
G03X1103188Y1238209I500J0D01*
G01X1104869D01*
G01X1070750D02*
X1071712D01*
G02X1072425Y1237496I0J-713D01*
G01Y1236911D01*
G03X1075245Y1234091I2820J0D01*
G01X1077596D01*
X1077597Y1234090D01*
X1095785D01*
G02X1097236Y1233489I0J-2052D01*
G02X1097328Y1233386I-882J-880D01*
G02X1097601Y1232608I-972J-778D01*
G01Y1231622D01*
G02X1097101Y1231122I-500J0D01*
G01X1095421D01*
X1095420Y1231123D01*
G01X1100932D02*
X1100931Y1231122D01*
X1099251D01*
G02X1098763Y1231508I-1J501D01*
G02X1098751Y1231622I489J109D01*
G01Y1232610D01*
G03X1098227Y1234105I-2395J0D01*
G03X1098050Y1234303I-1872J-1496D01*
G03X1095784Y1235240I-2264J-2266D01*
G01X1095783Y1235241D01*
X1075245D01*
G02X1073575Y1236911I0J1670D01*
G01Y1237496D01*
G02X1074288Y1238209I713J0D01*
G01X1075250D01*
G01Y1231122D02*
X1074288D01*
G03X1073575Y1230409I0J-713D01*
G01Y1229824D01*
G03X1075245Y1228154I1670J0D01*
G01X1099721D01*
G02X1101987Y1227217I2J-3203D01*
G02X1102164Y1227019I-1695J-1694D01*
G02X1102688Y1225524I-1871J-1495D01*
G01Y1224536D01*
G03X1103188Y1224036I500J0D01*
G01X1104869D01*
G01X1070750Y1323248D02*
X1071712D01*
G02X1072425Y1322535I0J-713D01*
G01Y1321950D01*
G03X1075245Y1319130I2820J0D01*
G01X1095785D01*
G02X1097236Y1318529I0J-2052D01*
G02X1097328Y1318426I-882J-880D01*
G02X1097601Y1317648I-972J-778D01*
G01Y1316662D01*
G02X1097101Y1316162I-500J0D01*
G01X1095420D01*
G01X1100932D02*
X1099251D01*
G02X1098751Y1316662I0J500D01*
G01Y1317650D01*
G03X1098227Y1319145I-2395J0D01*
G03X1098050Y1319343I-1872J-1496D01*
G03X1095784Y1320280I-2264J-2266D01*
G01X1075245D01*
G02X1073575Y1321950I0J1670D01*
G01Y1322535D01*
G02X1074288Y1323248I713J0D01*
G01X1075250D01*
G01X1070750Y1316161D02*
X1071712D01*
G02X1072425Y1315448I0J-713D01*
G01Y1314863D01*
G03X1075245Y1312043I2820J0D01*
G01X1099722D01*
G02X1101173Y1311442I0J-2052D01*
G02X1101265Y1311339I-882J-880D01*
G02X1101538Y1310561I-972J-778D01*
G01Y1309575D01*
G02X1101038Y1309075I-500J0D01*
G01X1099357D01*
G01X1075250Y1316161D02*
X1074288D01*
G03X1073575Y1315448I0J-713D01*
G01Y1314863D01*
G03X1075245Y1313193I1670J0D01*
G01X1099721D01*
G02X1101987Y1312256I2J-3203D01*
G02X1102164Y1312058I-1695J-1694D01*
G02X1102688Y1310563I-1871J-1495D01*
G01Y1309575D01*
G03X1103188Y1309075I500J0D01*
G01X1104869D01*
G01X1070750D02*
X1071712D01*
G02X1072425Y1308362I0J-713D01*
G01Y1307777D01*
G03X1075245Y1304957I2820J0D01*
G01X1095785D01*
G02X1097236Y1304356I0J-2052D01*
G02X1097328Y1304253I-882J-880D01*
G02X1097601Y1303475I-972J-778D01*
G01Y1302489D01*
G02X1097101Y1301989I-500J0D01*
G01X1095420D01*
G01X1100932D02*
X1099251D01*
G02X1098751Y1302489I0J500D01*
G01Y1303477D01*
G03X1098227Y1304972I-2395J0D01*
G03X1098050Y1305170I-1872J-1496D01*
G03X1095784Y1306107I-2264J-2266D01*
G01X1075245D01*
G02X1073575Y1307777I0J1670D01*
G01Y1308362D01*
G02X1074288Y1309075I713J0D01*
G01X1075250D01*
G01X1070750Y1301988D02*
X1071712D01*
G02X1072425Y1301275I0J-713D01*
G01Y1300690D01*
G03X1075245Y1297870I2820J0D01*
G01X1099722D01*
G02X1101173Y1297269I0J-2052D01*
G02X1101265Y1297166I-882J-880D01*
G02X1101538Y1296388I-972J-778D01*
G01Y1295402D01*
G02X1101038Y1294902I-500J0D01*
G01X1099357D01*
G01X1075250Y1301988D02*
X1074288D01*
G03X1073575Y1301275I0J-713D01*
G01Y1300690D01*
G03X1075245Y1299020I1670J0D01*
G01X1099721D01*
G02X1101987Y1298083I2J-3203D01*
G02X1102164Y1297885I-1695J-1694D01*
G02X1102688Y1296390I-1871J-1495D01*
G01Y1295402D01*
G03X1103188Y1294902I500J0D01*
G01X1104869D01*
G01X1070750D02*
X1071712D01*
G02X1072425Y1294189I0J-713D01*
G01Y1293604D01*
G03X1075245Y1290784I2820J0D01*
G01X1095785D01*
G02X1097236Y1290183I0J-2052D01*
G02X1097328Y1290080I-882J-880D01*
G02X1097601Y1289302I-972J-778D01*
G01Y1288316D01*
G02X1097101Y1287816I-500J0D01*
G01X1095420D01*
G01X1100932D02*
X1099251D01*
G02X1098751Y1288316I0J500D01*
G01Y1289304D01*
G03X1098227Y1290799I-2395J0D01*
G03X1098050Y1290997I-1872J-1496D01*
G03X1095784Y1291934I-2264J-2266D01*
G01X1075245D01*
G02X1073575Y1293604I0J1670D01*
G01Y1294189D01*
G02X1074288Y1294902I713J0D01*
G01X1075250D01*
G01X1070750Y1330335D02*
X1071712D01*
G02X1072425Y1329622I0J-713D01*
G01Y1329037D01*
G03X1075245Y1326217I2820J0D01*
G01X1099722D01*
G02X1101173Y1325616I0J-2052D01*
G02X1101265Y1325513I-882J-880D01*
G02X1101538Y1324735I-972J-778D01*
G01Y1323749D01*
G02X1101038Y1323249I-500J0D01*
G01X1099357D01*
G01X1075250Y1330335D02*
X1074288D01*
G03X1073575Y1329622I0J-713D01*
G01Y1329037D01*
G03X1075245Y1327367I1670J0D01*
G01X1099721D01*
G02X1101987Y1326430I2J-3203D01*
G02X1102164Y1326232I-1695J-1694D01*
G02X1102688Y1324737I-1871J-1495D01*
G01Y1323749D01*
G03X1103188Y1323249I500J0D01*
G01X1104869D01*
G01X1070750Y1415374D02*
X1071712D01*
G02X1072425Y1414661I0J-713D01*
G01Y1414076D01*
G03X1075245Y1411256I2820J0D01*
G01X1099722D01*
G02X1101173Y1410655I0J-2052D01*
G02X1101265Y1410552I-882J-880D01*
G02X1101538Y1409774I-972J-778D01*
G01Y1408788D01*
G02X1101038Y1408288I-500J0D01*
G01X1099357D01*
G01X1075250Y1415374D02*
X1074288D01*
G03X1073575Y1414661I0J-713D01*
G01Y1414076D01*
G03X1075245Y1412406I1670J0D01*
G01X1099721D01*
G02X1101987Y1411469I2J-3203D01*
G02X1102164Y1411271I-1695J-1694D01*
G02X1102688Y1409776I-1871J-1495D01*
G01Y1408788D01*
G03X1103188Y1408288I500J0D01*
G01X1104869D01*
G01X1070750Y1408287D02*
X1071712D01*
G02X1072425Y1407574I0J-713D01*
G01Y1406989D01*
G03X1075245Y1404169I2820J0D01*
G01X1095785D01*
G02X1097236Y1403568I0J-2052D01*
G02X1097328Y1403465I-882J-880D01*
G02X1097601Y1402687I-972J-778D01*
G01Y1401701D01*
G02X1097101Y1401201I-500J0D01*
G01X1095420D01*
G01X1100932D02*
X1099251D01*
G02X1098751Y1401701I0J500D01*
G01Y1402689D01*
G03X1098227Y1404184I-2395J0D01*
G03X1098050Y1404382I-1872J-1496D01*
G03X1095784Y1405319I-2264J-2266D01*
G01X1075245D01*
G02X1073575Y1406989I0J1670D01*
G01Y1407574D01*
G02X1074288Y1408287I713J0D01*
G01X1075250D01*
G01X1070750Y1401201D02*
X1071712D01*
G02X1072425Y1400488I0J-713D01*
G01Y1399903D01*
G03X1075245Y1397083I2820J0D01*
G01X1099722D01*
G02X1101173Y1396482I0J-2052D01*
G02X1101265Y1396379I-882J-880D01*
G02X1101538Y1395601I-972J-778D01*
G01Y1394615D01*
G02X1101038Y1394115I-500J0D01*
G01X1099357D01*
G01X1075250Y1401201D02*
X1074288D01*
G03X1073575Y1400488I0J-713D01*
G01Y1399903D01*
G03X1075245Y1398233I1670J0D01*
G01X1099721D01*
G02X1101987Y1397296I2J-3203D01*
G02X1102164Y1397098I-1695J-1694D01*
G02X1102688Y1395603I-1871J-1495D01*
G01Y1394615D01*
G03X1103188Y1394115I500J0D01*
G01X1104869D01*
G01X1070750Y1394114D02*
X1071712D01*
G02X1072425Y1393401I0J-713D01*
G01Y1392816D01*
G03X1075245Y1389996I2820J0D01*
G01X1095785D01*
G02X1097236Y1389395I0J-2052D01*
G02X1097328Y1389292I-882J-880D01*
G02X1097601Y1388514I-972J-778D01*
G01Y1387528D01*
G02X1097101Y1387028I-500J0D01*
G01X1095420D01*
G01X1100932D02*
X1099251D01*
G02X1098751Y1387528I0J500D01*
G01Y1388516D01*
G03X1098227Y1390011I-2395J0D01*
G03X1098050Y1390209I-1872J-1496D01*
G03X1095784Y1391146I-2264J-2266D01*
G01X1075245D01*
G02X1073575Y1392816I0J1670D01*
G01Y1393401D01*
G02X1074288Y1394114I713J0D01*
G01X1075250D01*
G01X1070750Y1387028D02*
X1071712D01*
G02X1072425Y1386315I0J-713D01*
G01Y1385730D01*
G03X1075245Y1382910I2820J0D01*
G01X1099722D01*
G02X1101173Y1382309I0J-2052D01*
G02X1101265Y1382206I-882J-880D01*
G02X1101538Y1381428I-972J-778D01*
G01Y1380442D01*
G02X1101038Y1379942I-500J0D01*
G01X1099357D01*
G01X1075250Y1387028D02*
X1074288D01*
G03X1073575Y1386315I0J-713D01*
G01Y1385730D01*
G03X1075245Y1384060I1670J0D01*
G01X1099721D01*
G02X1101987Y1383123I2J-3203D01*
G02X1102164Y1382925I-1695J-1694D01*
G02X1102688Y1381430I-1871J-1495D01*
G01Y1380442D01*
G03X1103188Y1379942I500J0D01*
G01X1104869D01*
G01X1070750Y1379941D02*
X1071712D01*
G02X1072425Y1379228I0J-713D01*
G01Y1378643D01*
G03X1075245Y1375823I2820J0D01*
G01X1095785D01*
G02X1097236Y1375222I0J-2052D01*
G02X1097328Y1375119I-882J-880D01*
G02X1097601Y1374341I-972J-778D01*
G01Y1373355D01*
G02X1097101Y1372855I-500J0D01*
G01X1095420D01*
G01X1100932D02*
X1099251D01*
G02X1098751Y1373355I0J500D01*
G01Y1374343D01*
G03X1098227Y1375838I-2395J0D01*
G03X1098050Y1376036I-1872J-1496D01*
G03X1095784Y1376973I-2264J-2266D01*
G01X1075245D01*
G02X1073575Y1378643I0J1670D01*
G01Y1379228D01*
G02X1074288Y1379941I713J0D01*
G01X1075250D01*
G01X1526925Y185742D02*
Y186721D01*
G03X1526229Y187417I-696J0D01*
G01X1523601D01*
X1523028Y187990D01*
X1522590Y188427D01*
X1512816Y211276D01*
X1512815D01*
X1502186Y236124D01*
X1244314Y612416D01*
X1192003Y848427D01*
X1219986Y974681D01*
X1192383Y1099160D01*
X1155622Y1156863D01*
X1155621D01*
X1154738Y1157059D01*
X1153932Y1158324D01*
X1154128Y1159208D01*
X1153322Y1160473D01*
X1152438Y1160669D01*
X1151632Y1161934D01*
X1151828Y1162817D01*
X1151022Y1164082D01*
X1150138Y1164278D01*
X1149332Y1165543D01*
X1149528Y1166427D01*
X1147703Y1169292D01*
X1147704D01*
X1135721Y1176929D01*
X1133597Y1177398D01*
X1128913D01*
G03X1127462Y1176797I0J-2052D01*
G03X1127097Y1175916I881J-881D01*
G01Y1174930D01*
G03X1127597Y1174430I500J0D01*
G01X1129278D01*
G01X1526925Y190242D02*
Y189263D01*
G02X1526229Y188567I-696J0D01*
G01X1524078D01*
X1523561Y189084D01*
X1503057Y237012D01*
X1502939Y237060D01*
X1245389Y612882D01*
X1193181Y848427D01*
X1221164Y974681D01*
X1193462Y1099607D01*
X1148537Y1170125D01*
X1136168Y1178008D01*
X1133723Y1178548D01*
X1128913D01*
G03X1126648Y1177610I0J-3203D01*
G03X1125947Y1175916I1695J-1693D01*
G01Y1174930D01*
G02X1125447Y1174430I-500J0D01*
G01X1123766D01*
G01X1651138Y185742D02*
Y186721D01*
G03X1650442Y187417I-696J0D01*
G01X1648272D01*
X1646807Y187805D01*
X1644386Y188447D01*
X1446029Y330312D01*
X1251366Y613306D01*
X1199086Y849107D01*
X1198937Y849341D01*
X1226467Y973479D01*
X1196926Y1106764D01*
X1162346Y1161039D01*
X1161462Y1161235D01*
X1160656Y1162500D01*
X1160852Y1163384D01*
X1160046Y1164649D01*
X1159162Y1164845D01*
X1158356Y1166110D01*
X1158552Y1166993D01*
X1157746Y1168258D01*
X1156863Y1168454D01*
X1156057Y1169719D01*
X1156252Y1170603D01*
X1153774Y1174493D01*
X1139070Y1183863D01*
X1138658Y1183955D01*
X1136268Y1184484D01*
X1132850D01*
G03X1131399Y1183883I0J-2052D01*
G03X1131034Y1183002I881J-881D01*
G01Y1182016D01*
G03X1131534Y1181516I500J0D01*
G01X1133215D01*
G01X1127703D02*
X1129384D01*
G03X1129884Y1182016I0J500D01*
G01Y1183002D01*
G02X1130585Y1184696I2396J1D01*
G02X1132850Y1185634I2265J-2265D01*
G01X1136394D01*
X1138497Y1185169D01*
X1139518Y1184942D01*
X1154607Y1175326D01*
X1198005Y1107211D01*
X1227645Y973479D01*
X1200163Y849557D01*
X1200165Y849554D01*
X1200209Y849356D01*
Y849355D01*
X1252441Y613774D01*
X1446863Y331131D01*
X1644884Y189505D01*
X1646515Y189073D01*
X1648422Y188567D01*
X1650442D01*
G03X1651138Y189263I0J696D01*
G01Y190242D01*
G01X1129278Y1188603D02*
X1127597D01*
G02X1127097Y1189103I0J500D01*
G01Y1190089D01*
G02X1127462Y1190970I1246J0D01*
G02X1128913Y1191571I1451J-1451D01*
G01X1134099D01*
X1141013Y1190036D01*
X1159782Y1178081D01*
X1162338Y1174067D01*
X1162142Y1173183D01*
X1162948Y1171918D01*
X1163831Y1171722D01*
X1164637Y1170457D01*
X1164441Y1169573D01*
X1165247Y1168308D01*
X1166130Y1168112D01*
X1166936Y1166847D01*
X1166740Y1165963D01*
X1167546Y1164698D01*
X1168429Y1164502D01*
X1202045Y1111716D01*
X1233250Y971017D01*
X1205918Y847805D01*
X1257075Y617342D01*
X1393465Y419050D01*
X1647683Y253971D01*
X1658382Y251697D01*
X1690063Y244962D01*
X1769179Y188374D01*
X1772787Y187417D01*
X1774654D01*
G02X1775350Y186721I0J-696D01*
G01Y185742D01*
G01X1123766Y1188603D02*
X1125447D01*
G03X1125947Y1189103I0J500D01*
G01Y1190089D01*
G02X1126648Y1191783I2396J1D01*
G02X1128913Y1192721I2265J-2265D01*
G01X1134226D01*
X1141460Y1191115D01*
X1160615Y1178914D01*
X1203124Y1112163D01*
X1234428Y971017D01*
X1207096Y847805D01*
X1258150Y617810D01*
X1394284Y419891D01*
X1648131Y255052D01*
X1690537Y246037D01*
X1769675Y189434D01*
X1772938Y188567D01*
X1774654D01*
G03X1775350Y189263I0J696D01*
G01Y190242D01*
G01X1899563Y185742D02*
Y186721D01*
G03X1898867Y187417I-696J0D01*
G01X1893544D01*
X1825293Y194043D01*
X1696691Y253091D01*
Y253093D01*
X1649534Y263114D01*
X1397543Y426407D01*
X1266625Y616702D01*
X1213977Y854145D01*
X1213914Y854397D01*
X1213973Y854663D01*
X1239624Y970380D01*
X1207584Y1115565D01*
X1172041Y1171363D01*
X1171157Y1171559D01*
X1170351Y1172824D01*
X1170547Y1173707D01*
X1169741Y1174972D01*
X1168857Y1175168D01*
X1168051Y1176433D01*
X1168247Y1177317D01*
X1167442Y1178582D01*
X1166558Y1178778D01*
X1165752Y1180043D01*
X1165948Y1180927D01*
X1165142Y1182192D01*
X1141270Y1197251D01*
X1134925Y1198658D01*
X1132850D01*
G03X1131399Y1198057I0J-2052D01*
G03X1131034Y1197176I881J-881D01*
G01Y1196190D01*
G03X1131534Y1195690I500J0D01*
G01X1133215D01*
G01X1127703D02*
X1129384D01*
G03X1129884Y1196190I0J500D01*
G01Y1197176D01*
G02X1130585Y1198870I2396J1D01*
G02X1132850Y1199808I2265J-2265D01*
G01X1135051D01*
X1141715Y1198331D01*
X1165974Y1183028D01*
X1208664Y1116012D01*
X1240802Y970379D01*
X1215096Y854413D01*
X1215097Y854409D01*
X1267700Y617171D01*
X1398361Y427248D01*
X1649981Y264195D01*
X1697055Y254192D01*
Y254190D01*
X1825597Y195169D01*
X1859078Y191919D01*
X1859077D01*
X1893600Y188567D01*
X1898867D01*
G03X1899563Y189263I0J696D01*
G01Y190242D01*
G01X1278500Y638498D02*
Y639477D01*
G03X1277804Y640173I-696J0D01*
G01X1276236D01*
X1273867Y640654D01*
X1272260Y641717D01*
X1269277Y646223D01*
X1221632Y860882D01*
X1245943Y970552D01*
X1233207Y1028249D01*
X1205185Y1155189D01*
X1168213Y1213269D01*
X1167329Y1213465D01*
X1166524Y1214730D01*
X1166720Y1215614D01*
X1165915Y1216879D01*
X1165031Y1217075D01*
X1164225Y1218341D01*
X1164422Y1219224D01*
X1163616Y1220490D01*
X1162733Y1220686D01*
X1161927Y1221951D01*
X1162123Y1222835D01*
X1151607Y1239355D01*
X1139473Y1247084D01*
X1134155Y1248264D01*
X1128913D01*
G03X1127462Y1247663I0J-2052D01*
G03X1127097Y1246782I881J-881D01*
G01Y1245796D01*
G03X1127597Y1245296I500J0D01*
G01X1129278D01*
G01X1123766D02*
X1125447D01*
G03X1125947Y1245796I0J500D01*
G01Y1246782D01*
G02X1126648Y1248476I2396J1D01*
G02X1128913Y1249414I2265J-2265D01*
G01X1134282D01*
X1139920Y1248163D01*
X1152440Y1240188D01*
X1206265Y1155636D01*
X1234330Y1028497D01*
X1247121Y970551D01*
X1222810Y860882D01*
X1270354Y646680D01*
X1273090Y642547D01*
X1274315Y641737D01*
X1276350Y641323D01*
X1277804D01*
G03X1278500Y642019I0J696D01*
G01Y642998D01*
G01X1402713Y638498D02*
Y639477D01*
G03X1402017Y640173I-696J0D01*
G01X1400631D01*
X1399092Y640520D01*
X1397879Y641284D01*
X1394211Y646724D01*
X1392912Y648650D01*
X1378232Y714855D01*
X1333448Y916822D01*
X1229854Y1079428D01*
X1212953Y1155663D01*
X1175511Y1214472D01*
X1174628Y1214668D01*
X1173822Y1215933D01*
X1174018Y1216817D01*
X1173213Y1218082D01*
X1172329Y1218278D01*
X1171524Y1219544D01*
X1171720Y1220427D01*
X1170914Y1221693D01*
X1170031Y1221889D01*
X1169225Y1223154D01*
X1169421Y1224038D01*
X1155672Y1245634D01*
X1142177Y1254226D01*
X1137129Y1255350D01*
X1132850D01*
G03X1131399Y1254749I0J-2052D01*
G03X1131034Y1253868I881J-881D01*
G01Y1252882D01*
G03X1131534Y1252382I500J0D01*
G01X1133215D01*
G01X1127703D02*
X1129384D01*
G03X1129884Y1252882I0J500D01*
G01Y1253868D01*
G02X1130585Y1255562I2396J1D01*
G02X1132850Y1256500I2265J-2265D01*
G01X1137256D01*
X1142624Y1255305D01*
X1156505Y1246467D01*
X1214032Y1156110D01*
X1230933Y1079875D01*
X1334527Y917269D01*
X1393988Y649112D01*
X1395061Y647522D01*
X1395165Y647368D01*
X1398697Y642128D01*
X1399538Y641599D01*
X1400758Y641323D01*
X1402017D01*
G03X1402713Y642019I0J696D01*
G01Y642998D01*
G01X1129278Y1259469D02*
X1127597D01*
G02X1127097Y1259969I0J500D01*
G01Y1260955D01*
G02X1127462Y1261836I1246J0D01*
G02X1128913Y1262437I1451J-1451D01*
G01X1131803D01*
X1131804Y1262438D01*
X1134458D01*
X1144046Y1260314D01*
X1161726Y1249044D01*
X1175035Y1228235D01*
X1174840Y1227351D01*
X1175649Y1226088D01*
X1176533Y1225893D01*
X1177341Y1224630D01*
X1177147Y1223746D01*
X1177955Y1222482D01*
X1178839Y1222288D01*
X1179647Y1221024D01*
X1179453Y1220140D01*
X1180261Y1218876D01*
X1181145Y1218682D01*
X1223276Y1152809D01*
X1238359Y1084780D01*
X1379902Y862658D01*
X1520829Y641502D01*
X1522948Y640173D01*
X1526229D01*
G02X1526925Y639477I0J-696D01*
G01Y638498D01*
G01Y642998D02*
Y642019D01*
G02X1526229Y641323I-696J0D01*
G01X1523279D01*
X1521660Y642339D01*
X1380872Y863276D01*
X1239438Y1085227D01*
X1224355Y1153257D01*
X1162559Y1249878D01*
X1144493Y1261393D01*
X1134584Y1263588D01*
X1132188D01*
X1132187Y1263587D01*
X1128913D01*
G03X1126648Y1262649I0J-3203D01*
G03X1125947Y1260955I1695J-1693D01*
G01Y1259969D01*
G02X1125447Y1259469I-500J0D01*
G01X1123766D01*
G01X1651138Y638498D02*
Y639477D01*
G03X1650442Y640173I-696J0D01*
G01X1648461D01*
X1454559Y761362D01*
X1403396Y841607D01*
X1246784Y1087240D01*
X1232842Y1150116D01*
X1186891Y1222215D01*
X1186008Y1222411D01*
X1185201Y1223676D01*
X1185397Y1224560D01*
X1184591Y1225825D01*
X1183707Y1226020D01*
X1182901Y1227285D01*
X1183097Y1228169D01*
X1182291Y1229434D01*
X1181407Y1229630D01*
X1180601Y1230895D01*
X1180797Y1231778D01*
X1167498Y1252645D01*
X1144021Y1267602D01*
X1135353Y1269524D01*
X1132850D01*
G03X1131399Y1268923I0J-2052D01*
G03X1131034Y1268042I881J-881D01*
G01Y1267056D01*
G03X1131534Y1266556I500J0D01*
G01X1133215D01*
G01X1651138Y642998D02*
Y642019D01*
G02X1650442Y641323I-696J0D01*
G01X1648791D01*
X1552006Y701815D01*
Y701814D01*
X1455390Y762200D01*
X1404028Y842757D01*
X1404027D01*
X1247863Y1087687D01*
X1233921Y1150563D01*
X1168331Y1253478D01*
X1144468Y1268681D01*
X1135479Y1270674D01*
X1132850D01*
G03X1130585Y1269736I0J-3203D01*
G03X1129884Y1268042I1695J-1693D01*
G01Y1267056D01*
G02X1129384Y1266556I-500J0D01*
G01X1127703D01*
G01X1129278Y1273642D02*
X1127597D01*
G02X1127097Y1274142I0J500D01*
G01Y1275128D01*
G02X1127462Y1276009I1246J0D01*
G02X1128913Y1276610I1451J-1451D01*
G01X1132270D01*
X1145998Y1273573D01*
X1173250Y1256210D01*
X1186895Y1234788D01*
X1186699Y1233904D01*
X1187505Y1232639D01*
X1188388Y1232443D01*
X1189194Y1231178D01*
X1188998Y1230294D01*
X1189804Y1229029D01*
X1190688Y1228833D01*
X1191493Y1227568D01*
X1191297Y1226684D01*
X1192103Y1225419D01*
X1192987Y1225223D01*
X1222877Y1178297D01*
X1252768Y1131370D01*
X1266169Y1070911D01*
X1396440Y874075D01*
X1557023Y773710D01*
X1664410Y667309D01*
X1720016Y640173D01*
X1724654D01*
G02X1725350Y639477I0J-696D01*
G01Y638498D01*
G01X1123766Y1273642D02*
X1125447D01*
G03X1125947Y1274142I0J500D01*
G01Y1275128D01*
G02X1126648Y1276822I2396J1D01*
G02X1128913Y1277760I2265J-2265D01*
G01X1132396D01*
X1146445Y1274652D01*
X1174083Y1257043D01*
X1253847Y1131817D01*
X1267246Y1071368D01*
X1397262Y874919D01*
X1557742Y774618D01*
X1665085Y668260D01*
X1720282Y641323D01*
X1724654D01*
G03X1725350Y642019I0J696D01*
G01Y642998D01*
G01X1899563Y638498D02*
Y639477D01*
G03X1898867Y640173I-696J0D01*
G01X1896496D01*
X1896419Y640250D01*
X1896082Y640588D01*
X1895427Y641244D01*
X1894691Y641982D01*
X1816957Y759535D01*
X1773132Y793349D01*
X1746153Y829745D01*
X1719269Y866013D01*
X1693609Y885927D01*
X1487015Y927077D01*
X1487004Y927084D01*
X1485119Y928333D01*
X1291173Y1056703D01*
X1267816Y1091984D01*
X1257822Y1137065D01*
X1194596Y1236323D01*
X1193713Y1236519D01*
X1192907Y1237784D01*
X1193103Y1238667D01*
X1192297Y1239932D01*
X1191413Y1240128D01*
X1190607Y1241394D01*
X1190803Y1242277D01*
X1189997Y1243542D01*
X1189114Y1243738D01*
X1188308Y1245003D01*
X1188504Y1245887D01*
X1179959Y1259302D01*
X1143728Y1282383D01*
X1137804Y1283697D01*
X1132850D01*
G03X1131399Y1283096I0J-2052D01*
G03X1131034Y1282215I881J-881D01*
G01Y1281229D01*
G03X1131534Y1280729I500J0D01*
G01X1133215D01*
G01X1899563Y642998D02*
Y642019D01*
G02X1898867Y641323I-696J0D01*
G01X1896974D01*
X1896897Y641400D01*
X1895587Y642713D01*
X1817811Y760329D01*
X1773961Y794162D01*
X1720099Y866825D01*
X1694100Y887002D01*
X1487461Y928161D01*
X1485754Y929292D01*
X1292003Y1057533D01*
X1268893Y1092441D01*
X1258901Y1137512D01*
X1180792Y1260135D01*
X1144175Y1283462D01*
X1137930Y1284847D01*
X1132850D01*
G03X1130585Y1283909I0J-3203D01*
G03X1129884Y1282215I1695J-1693D01*
G01Y1281229D01*
G02X1129384Y1280729I-500J0D01*
G01X1127703D01*
G01X1775350Y1091254D02*
Y1092233D01*
G03X1774654Y1092929I-696J0D01*
G01X1771207D01*
X1607855Y1201052D01*
X1461964Y1230734D01*
X1378412Y1284515D01*
X1377582Y1284335D01*
X1376321Y1285147D01*
X1376141Y1285976D01*
X1374880Y1286788D01*
X1374051Y1286609D01*
X1372790Y1287420D01*
X1372610Y1288250D01*
X1371349Y1289062D01*
X1370519Y1288882D01*
X1369258Y1289694D01*
X1369078Y1290523D01*
X1316427Y1324414D01*
X1148454Y1361650D01*
X1128913D01*
G03X1127462Y1361049I0J-2052D01*
G03X1127097Y1360168I881J-881D01*
G01Y1359182D01*
G03X1127597Y1358682I500J0D01*
G01X1129278D01*
G01X1775350Y1095754D02*
Y1094775D01*
G02X1774654Y1094079I-696J0D01*
G01X1771554D01*
X1608304Y1202135D01*
X1462405Y1231818D01*
X1316877Y1325493D01*
X1148580Y1362800D01*
X1128913D01*
G03X1126648Y1361862I0J-3203D01*
G03X1125947Y1360168I1695J-1693D01*
G01Y1359182D01*
G02X1125447Y1358682I-500J0D01*
G01X1123766D01*
G01X1133215Y1365768D02*
X1131534D01*
G02X1131034Y1366268I0J500D01*
G01Y1367254D01*
G02X1131399Y1368135I1246J0D01*
G02X1132850Y1368736I1451J-1451D01*
G01X1144920D01*
X1325536Y1328695D01*
X1466068Y1239152D01*
X1467538Y1238853D01*
X1468037Y1238098D01*
X1469507Y1237799D01*
X1470262Y1238299D01*
X1471732Y1238000D01*
X1472232Y1237245D01*
X1473701Y1236946D01*
X1474456Y1237445D01*
X1475926Y1237146D01*
X1476426Y1236392D01*
X1477895Y1236093D01*
X1478650Y1236592D01*
X1621652Y1207497D01*
X1777230Y1175842D01*
X1783807Y1171489D01*
X1783808D01*
X1833178Y1138811D01*
X1882549Y1106132D01*
X1888548Y1097073D01*
X1893918Y1093518D01*
X1894101Y1093482D01*
X1896422Y1092929D01*
X1898867D01*
G02X1899563Y1092233I0J-696D01*
G01Y1091254D01*
G01Y1095754D02*
Y1094775D01*
G02X1898867Y1094079I-696J0D01*
G01X1896558D01*
X1894367Y1094601D01*
X1889378Y1097903D01*
X1883379Y1106962D01*
X1777679Y1176925D01*
X1466508Y1240237D01*
X1466507D01*
X1325983Y1329774D01*
X1145046Y1369886D01*
X1132850D01*
G03X1130585Y1368948I0J-3203D01*
G03X1129884Y1367254I1695J-1693D01*
G01Y1366268D01*
G02X1129384Y1365768I-500J0D01*
G01X1127703D01*
G01X1278500Y1091254D02*
Y1092233D01*
G03X1277804Y1092929I-696J0D01*
G01X1275986D01*
X1273625Y1094429D01*
X1258807Y1161219D01*
X1247853Y1178412D01*
X1246970Y1178608D01*
X1246164Y1179873D01*
X1246360Y1180757D01*
X1245554Y1182022D01*
X1244670Y1182218D01*
X1243864Y1183483D01*
X1244060Y1184366D01*
X1243254Y1185631D01*
X1242370Y1185827D01*
X1241564Y1187092D01*
X1241760Y1187976D01*
X1156784Y1321358D01*
X1139634Y1332283D01*
X1135030Y1333304D01*
X1135029Y1333303D01*
X1128913D01*
G03X1127462Y1332702I0J-2052D01*
G03X1127097Y1331821I881J-881D01*
G01Y1330835D01*
G03X1127597Y1330335I500J0D01*
G01X1129278D01*
G01X1278500Y1095754D02*
Y1094775D01*
G02X1277804Y1094079I-696J0D01*
G01X1276321D01*
X1274645Y1095144D01*
X1259886Y1161666D01*
X1157617Y1322191D01*
X1140081Y1333362D01*
X1135156Y1334454D01*
X1135155Y1334453D01*
X1128913D01*
G03X1126648Y1333515I0J-3203D01*
G03X1125947Y1331821I1695J-1693D01*
G01Y1330835D01*
G02X1125447Y1330335I-500J0D01*
G01X1123766D01*
G01X1402713Y1091254D02*
Y1092233D01*
G03X1402017Y1092929I-696J0D01*
G01X1399855D01*
X1396944Y1093518D01*
X1368553Y1112310D01*
X1334705Y1163447D01*
X1214842Y1242788D01*
X1213680Y1244611D01*
X1212797Y1244807D01*
X1211991Y1246072D01*
X1212187Y1246956D01*
X1211381Y1248221D01*
X1210497Y1248417D01*
X1209691Y1249682D01*
X1209887Y1250566D01*
X1209081Y1251831D01*
X1208197Y1252027D01*
X1207391Y1253292D01*
X1207587Y1254175D01*
X1159412Y1329793D01*
X1145610Y1338577D01*
X1137421Y1340390D01*
X1132850D01*
G03X1131399Y1339789I0J-2052D01*
G03X1131034Y1338908I881J-881D01*
G01Y1337922D01*
G03X1131534Y1337422I500J0D01*
G01X1133215D01*
G01X1402713Y1095754D02*
Y1094775D01*
G02X1402017Y1094079I-696J0D01*
G01X1399971D01*
X1397392Y1094601D01*
X1369383Y1113140D01*
X1335534Y1164279D01*
X1335339Y1164409D01*
Y1164408D01*
X1335338D01*
X1215681Y1243613D01*
Y1243612D01*
X1160245Y1330626D01*
X1146057Y1339657D01*
X1137547Y1341540D01*
X1132850D01*
G03X1130585Y1340602I0J-3203D01*
G03X1129884Y1338908I1695J-1693D01*
G01Y1337922D01*
G02X1129384Y1337422I-500J0D01*
G01X1127703D01*
G01X1526925Y1091254D02*
Y1092233D01*
G03X1526229Y1092929I-696J0D01*
G01X1523497D01*
X1413660Y1165627D01*
X1380503Y1172374D01*
X1202932Y1289908D01*
X1201908Y1291517D01*
X1201024Y1291713D01*
X1200219Y1292979D01*
X1200415Y1293862D01*
X1199610Y1295128D01*
X1198726Y1295324D01*
X1197921Y1296590D01*
X1198117Y1297473D01*
X1197312Y1298739D01*
X1196429Y1298935D01*
X1195623Y1300200D01*
X1195819Y1301084D01*
X1181813Y1323093D01*
X1148259Y1344469D01*
X1134682Y1347476D01*
X1128913D01*
G03X1127462Y1346875I0J-2052D01*
G03X1127097Y1345994I881J-881D01*
G01Y1345008D01*
G03X1127597Y1344508I500J0D01*
G01X1129278D01*
G01X1526925Y1095754D02*
Y1094775D01*
G02X1526229Y1094079I-696J0D01*
G01X1523844D01*
X1468928Y1130426D01*
X1468929D01*
X1414109Y1166710D01*
X1380952Y1173457D01*
X1203771Y1290732D01*
X1182647Y1323926D01*
X1148706Y1345548D01*
X1134808Y1348626D01*
X1128913D01*
G03X1126648Y1347688I0J-3203D01*
G03X1125947Y1345994I1695J-1693D01*
G01Y1345008D01*
G02X1125447Y1344508I-500J0D01*
G01X1123766D01*
G01X1651138Y1091254D02*
Y1092233D01*
G03X1650442Y1092929I-696J0D01*
G01X1647066D01*
X1457582Y1173048D01*
X1378124Y1190664D01*
X1377408Y1190208D01*
X1375944Y1190533D01*
X1375488Y1191249D01*
X1374023Y1191573D01*
X1373308Y1191117D01*
X1371843Y1191442D01*
X1371387Y1192158D01*
X1369923Y1192482D01*
X1369207Y1192026D01*
X1367743Y1192351D01*
X1367287Y1193067D01*
X1358760Y1194957D01*
X1209419Y1293810D01*
X1189005Y1325865D01*
X1147625Y1352227D01*
X1137085Y1354563D01*
X1132850D01*
G03X1131399Y1353962I0J-2052D01*
G03X1131034Y1353081I881J-881D01*
G01Y1352095D01*
G03X1131534Y1351595I500J0D01*
G01X1133215D01*
G01X1651138Y1095754D02*
Y1094775D01*
G02X1650442Y1094079I-696J0D01*
G01X1647300D01*
X1457934Y1174149D01*
X1359217Y1196034D01*
X1210258Y1294634D01*
X1189838Y1326698D01*
X1148072Y1353306D01*
X1137211Y1355713D01*
X1132850D01*
G03X1130585Y1354775I0J-3203D01*
G03X1129884Y1353081I1695J-1693D01*
G01Y1352095D01*
G02X1129384Y1351595I-500J0D01*
G01X1127703D01*
G54D26*
X93100Y971000D03*
X159800Y559000D03*
X741883Y865289D03*
X703883Y911889D03*
X707332Y939902D03*
X750968Y896298D03*
X961000Y1516900D03*
X1733218Y991829D03*
X1891877Y877003D03*
G54D17*
X63463Y987125D03*
X129763Y560525D03*
X156941Y998444D03*
X223641Y586444D03*
X1702761Y1009647D03*
X1798741Y1010444D03*
G54D35*
X129000Y997700D03*
X195500Y585700D03*
X749383Y915989D03*
X855400Y458500D03*
X1429400Y558100D03*
Y562100D03*
X1770800Y1009700D03*
X1886450Y880323D03*
X1900200Y938000D03*
Y921000D03*
Y925000D03*
G54D62*
X720782Y927445D03*
Y905559D03*
G54D53*
X736988Y885549D03*
X724776D03*
X736988Y891455D03*
X724776D03*
G54D71*
X929331Y16536D03*
X937205Y20473D03*
Y12599D03*
X929331Y63780D03*
X937205Y67717D03*
X929331Y48032D03*
Y40158D03*
Y32284D03*
Y24410D03*
X937205Y51969D03*
Y44095D03*
Y36221D03*
Y28347D03*
X929331Y111024D03*
Y103150D03*
Y95276D03*
Y87402D03*
Y79528D03*
Y71654D03*
X937205Y114961D03*
Y107087D03*
Y99213D03*
Y91339D03*
Y83465D03*
Y75591D03*
X929331Y166142D03*
Y158268D03*
Y150394D03*
Y142520D03*
Y134646D03*
Y126772D03*
Y118898D03*
X937205Y162205D03*
Y154331D03*
Y146457D03*
Y138583D03*
Y130709D03*
Y122835D03*
X929331Y213386D03*
Y205512D03*
Y197638D03*
Y189764D03*
Y181890D03*
Y174016D03*
X937205Y209449D03*
Y201575D03*
Y193701D03*
Y185827D03*
Y177953D03*
Y170079D03*
X929331Y260630D03*
Y252756D03*
Y244882D03*
Y237008D03*
Y229134D03*
Y221260D03*
X937205Y256693D03*
Y248819D03*
Y240945D03*
Y233071D03*
Y225197D03*
Y217323D03*
X929331Y307874D03*
Y300000D03*
Y292126D03*
Y284252D03*
Y276378D03*
Y268504D03*
X937205Y303937D03*
Y296063D03*
Y288189D03*
Y280315D03*
Y272441D03*
Y264567D03*
X929331Y339371D03*
Y331496D03*
Y323622D03*
Y315748D03*
X937205Y335434D03*
Y327559D03*
Y319685D03*
Y311811D03*
X929331Y403543D03*
Y395669D03*
X937205Y407480D03*
Y399606D03*
Y391732D03*
X929331Y450787D03*
Y442913D03*
X937205Y454724D03*
Y446850D03*
X929331Y427165D03*
Y419291D03*
Y411417D03*
X937205Y431102D03*
Y423228D03*
Y415354D03*
X929331Y498031D03*
Y490157D03*
Y482283D03*
Y474409D03*
Y466535D03*
Y458661D03*
X937205Y501968D03*
Y494094D03*
Y486220D03*
Y478346D03*
Y470472D03*
Y462598D03*
X929331Y553149D03*
Y545275D03*
Y537401D03*
Y529527D03*
Y521653D03*
Y513779D03*
Y505905D03*
X937205Y549212D03*
Y541338D03*
Y533464D03*
Y525590D03*
Y517716D03*
Y509842D03*
X929331Y600393D03*
Y592519D03*
Y584645D03*
Y576771D03*
Y568897D03*
Y561023D03*
X937205Y596456D03*
Y588582D03*
Y580708D03*
Y572834D03*
Y564960D03*
Y557086D03*
X929331Y647637D03*
Y639763D03*
Y631889D03*
Y624015D03*
Y616141D03*
Y608267D03*
X937205Y643700D03*
Y635826D03*
Y627952D03*
Y620078D03*
Y612204D03*
Y604330D03*
X929331Y694881D03*
Y687007D03*
Y679133D03*
Y671259D03*
Y663385D03*
Y655511D03*
X937205Y690944D03*
Y683070D03*
Y675196D03*
Y667322D03*
Y659448D03*
Y651574D03*
X929331Y718504D03*
Y710629D03*
Y702755D03*
X937205Y714567D03*
Y706692D03*
Y698818D03*
X954921Y16536D03*
X947047Y20473D03*
Y12599D03*
X954921Y63780D03*
X947047Y67717D03*
X954921Y48032D03*
Y40158D03*
Y32284D03*
Y24410D03*
X947047Y51969D03*
Y44095D03*
Y36221D03*
Y28347D03*
X954921Y111024D03*
Y103150D03*
Y95276D03*
Y87402D03*
Y79528D03*
Y71654D03*
X947047Y114961D03*
Y107087D03*
Y99213D03*
Y91339D03*
Y83465D03*
Y75591D03*
X954921Y166142D03*
Y158268D03*
Y150394D03*
Y142520D03*
Y134646D03*
Y126772D03*
Y118898D03*
X947047Y162205D03*
Y154331D03*
Y146457D03*
Y138583D03*
Y130709D03*
Y122835D03*
X954921Y213386D03*
Y205512D03*
Y197638D03*
Y189764D03*
Y181890D03*
Y174016D03*
X947047Y209449D03*
Y201575D03*
Y193701D03*
Y185827D03*
Y177953D03*
Y170079D03*
X954921Y260630D03*
Y252756D03*
Y244882D03*
Y237008D03*
Y229134D03*
Y221260D03*
X947047Y256693D03*
Y248819D03*
Y240945D03*
Y233071D03*
Y225197D03*
Y217323D03*
X954921Y307874D03*
Y300000D03*
Y292126D03*
Y284252D03*
Y276378D03*
Y268504D03*
X947047Y303937D03*
Y296063D03*
Y288189D03*
Y280315D03*
Y272441D03*
Y264567D03*
X954921Y339371D03*
Y331496D03*
Y323622D03*
Y315748D03*
X947047Y335434D03*
Y327559D03*
Y319685D03*
Y311811D03*
X954921Y403543D03*
Y395669D03*
X947047Y407480D03*
Y399606D03*
Y391732D03*
X954921Y450787D03*
Y442913D03*
X947047Y454724D03*
Y446850D03*
X954921Y427165D03*
Y419291D03*
Y411417D03*
X947047Y431102D03*
Y423228D03*
Y415354D03*
X954921Y498031D03*
Y490157D03*
Y482283D03*
Y474409D03*
Y466535D03*
Y458661D03*
X947047Y501968D03*
Y494094D03*
Y486220D03*
Y478346D03*
Y470472D03*
Y462598D03*
X954921Y553149D03*
Y545275D03*
Y537401D03*
Y529527D03*
Y521653D03*
Y513779D03*
Y505905D03*
X947047Y549212D03*
Y541338D03*
Y533464D03*
Y525590D03*
Y517716D03*
Y509842D03*
X954921Y600393D03*
Y592519D03*
Y584645D03*
Y576771D03*
Y568897D03*
Y561023D03*
X947047Y596456D03*
Y588582D03*
Y580708D03*
Y572834D03*
Y564960D03*
Y557086D03*
X954921Y647637D03*
Y639763D03*
Y631889D03*
Y624015D03*
Y616141D03*
Y608267D03*
X947047Y643700D03*
Y635826D03*
Y627952D03*
Y620078D03*
Y612204D03*
Y604330D03*
X954921Y694881D03*
Y687007D03*
Y679133D03*
Y671259D03*
Y663385D03*
Y655511D03*
X947047Y690944D03*
Y683070D03*
Y675196D03*
Y667322D03*
Y659448D03*
Y651574D03*
X954921Y718504D03*
Y710629D03*
Y702755D03*
X947047Y714567D03*
Y706692D03*
Y698818D03*
X988795Y1571058D03*
Y1576658D03*
X1026106Y1545595D03*
Y1539995D03*
X1031706Y1545595D03*
Y1539995D03*
X1020574Y1540059D03*
Y1545659D03*
X1039758Y1559605D03*
X1014974Y1540059D03*
Y1545659D03*
X1039358Y1565405D03*
X1033717Y1563634D03*
X1028223Y1563763D03*
X1022623D03*
X994305Y1566342D03*
X1017023Y1563763D03*
X1011476Y1565175D03*
X1005658Y1565005D03*
X1000058D03*
X1039958Y1553705D03*
Y1548105D03*
Y1542505D03*
X1039358Y1571005D03*
Y1576605D03*
X1005658Y1575905D03*
X1033917Y1574834D03*
X1033717Y1569234D03*
X1000058Y1575905D03*
X1028423Y1574963D03*
X1028223Y1569363D03*
X994460Y1577240D03*
X1022823Y1574963D03*
X1022623Y1569363D03*
X1017223Y1574963D03*
X1017023Y1569363D03*
X994305Y1571942D03*
X1011676Y1576375D03*
X1011476Y1570775D03*
X1005658Y1570605D03*
X1000058D03*
X1078358Y1561105D03*
Y1566705D03*
X1072758Y1561105D03*
Y1566705D03*
X1067158Y1561105D03*
Y1566705D03*
X1061558Y1561105D03*
Y1566705D03*
X1055768Y1566675D03*
X1055418Y1560785D03*
X1055618Y1554885D03*
Y1549285D03*
Y1543685D03*
X1078358Y1572305D03*
X1072758D03*
X1067158D03*
X1061558D03*
X1055768Y1572275D03*
Y1577875D03*
X1123031Y16536D03*
X1097441D03*
X1115157Y20473D03*
Y12599D03*
X1105315Y20473D03*
Y12599D03*
X1123031Y63780D03*
X1097441D03*
X1115157Y67717D03*
X1105315D03*
X1123031Y48032D03*
Y40158D03*
Y32284D03*
Y24410D03*
X1097441Y48032D03*
Y40158D03*
Y32284D03*
Y24410D03*
X1115157Y51969D03*
Y44095D03*
Y36221D03*
Y28347D03*
X1105315Y51969D03*
Y44095D03*
Y36221D03*
Y28347D03*
X1123031Y111024D03*
Y103150D03*
Y95276D03*
Y87402D03*
Y79528D03*
Y71654D03*
X1097441Y111024D03*
Y103150D03*
Y95276D03*
Y87402D03*
Y79528D03*
Y71654D03*
X1115157Y114961D03*
Y107087D03*
Y99213D03*
Y91339D03*
Y83465D03*
Y75591D03*
X1105315Y114961D03*
Y107087D03*
Y99213D03*
Y91339D03*
Y83465D03*
Y75591D03*
X1123031Y166142D03*
Y158268D03*
Y150394D03*
Y142520D03*
Y134646D03*
Y126772D03*
Y118898D03*
X1097441Y166142D03*
Y158268D03*
Y150394D03*
Y142520D03*
Y134646D03*
Y126772D03*
Y118898D03*
X1115157Y162205D03*
Y154331D03*
Y146457D03*
Y138583D03*
Y130709D03*
Y122835D03*
X1105315Y162205D03*
Y154331D03*
Y146457D03*
Y138583D03*
Y130709D03*
Y122835D03*
X1123031Y213386D03*
Y205512D03*
Y197638D03*
Y189764D03*
Y181890D03*
Y174016D03*
X1097441Y213386D03*
Y205512D03*
Y197638D03*
Y189764D03*
Y181890D03*
Y174016D03*
X1115157Y209449D03*
Y201575D03*
Y193701D03*
Y185827D03*
Y177953D03*
Y170079D03*
X1105315Y209449D03*
Y201575D03*
Y193701D03*
Y185827D03*
Y177953D03*
Y170079D03*
X1123031Y260630D03*
Y252756D03*
Y244882D03*
Y237008D03*
Y229134D03*
Y221260D03*
X1097441Y260630D03*
Y252756D03*
Y244882D03*
Y237008D03*
Y229134D03*
Y221260D03*
X1115157Y256693D03*
Y248819D03*
Y240945D03*
Y233071D03*
Y225197D03*
Y217323D03*
X1105315Y256693D03*
Y248819D03*
Y240945D03*
Y233071D03*
Y225197D03*
Y217323D03*
X1123031Y307874D03*
Y300000D03*
Y292126D03*
Y284252D03*
Y276378D03*
Y268504D03*
X1097441Y307874D03*
Y300000D03*
Y292126D03*
Y284252D03*
Y276378D03*
Y268504D03*
X1115157Y303937D03*
Y296063D03*
Y288189D03*
Y280315D03*
Y272441D03*
Y264567D03*
X1105315Y303937D03*
Y296063D03*
Y288189D03*
Y280315D03*
Y272441D03*
Y264567D03*
X1123031Y339371D03*
Y331496D03*
Y323622D03*
Y315748D03*
X1097441Y339371D03*
Y331496D03*
Y323622D03*
Y315748D03*
X1115157Y335434D03*
Y327559D03*
Y319685D03*
Y311811D03*
X1105315Y335434D03*
Y327559D03*
Y319685D03*
Y311811D03*
X1123031Y403543D03*
Y395669D03*
X1097441Y403543D03*
Y395669D03*
X1115157Y407480D03*
Y399606D03*
Y391732D03*
X1105315Y407480D03*
Y399606D03*
Y391732D03*
X1123031Y450787D03*
Y442913D03*
X1097441Y450787D03*
Y442913D03*
X1115157Y454724D03*
Y446850D03*
X1105315Y454724D03*
Y446850D03*
X1123031Y427165D03*
Y419291D03*
Y411417D03*
X1097441Y427165D03*
Y419291D03*
Y411417D03*
X1115157Y431102D03*
Y423228D03*
Y415354D03*
X1105315Y431102D03*
Y423228D03*
Y415354D03*
X1123031Y498031D03*
Y490157D03*
Y482283D03*
Y474409D03*
Y466535D03*
Y458661D03*
X1097441Y498031D03*
Y490157D03*
Y482283D03*
Y474409D03*
Y466535D03*
Y458661D03*
X1115157Y501968D03*
Y494094D03*
Y486220D03*
Y478346D03*
Y470472D03*
Y462598D03*
X1105315Y501968D03*
Y494094D03*
Y486220D03*
Y478346D03*
Y470472D03*
Y462598D03*
X1123031Y553149D03*
Y545275D03*
Y537401D03*
Y529527D03*
Y521653D03*
Y513779D03*
Y505905D03*
X1097441Y553149D03*
Y545275D03*
Y537401D03*
Y529527D03*
Y521653D03*
Y513779D03*
Y505905D03*
X1115157Y549212D03*
Y541338D03*
Y533464D03*
Y525590D03*
Y517716D03*
Y509842D03*
X1105315Y549212D03*
Y541338D03*
Y533464D03*
Y525590D03*
Y517716D03*
Y509842D03*
X1123031Y600393D03*
Y592519D03*
Y584645D03*
Y576771D03*
Y568897D03*
Y561023D03*
X1097441Y600393D03*
Y592519D03*
Y584645D03*
Y576771D03*
Y568897D03*
Y561023D03*
X1115157Y596456D03*
Y588582D03*
Y580708D03*
Y572834D03*
Y564960D03*
Y557086D03*
X1105315Y596456D03*
Y588582D03*
Y580708D03*
Y572834D03*
Y564960D03*
Y557086D03*
X1123031Y647637D03*
Y639763D03*
Y631889D03*
Y624015D03*
Y616141D03*
Y608267D03*
X1097441Y647637D03*
Y639763D03*
Y631889D03*
Y624015D03*
Y616141D03*
Y608267D03*
X1115157Y643700D03*
Y635826D03*
Y627952D03*
Y620078D03*
Y612204D03*
Y604330D03*
X1105315Y643700D03*
Y635826D03*
Y627952D03*
Y620078D03*
Y612204D03*
Y604330D03*
X1123031Y694881D03*
Y687007D03*
Y679133D03*
Y671259D03*
Y663385D03*
Y655511D03*
X1097441Y694881D03*
Y687007D03*
Y679133D03*
Y671259D03*
Y663385D03*
Y655511D03*
X1115157Y690944D03*
Y683070D03*
Y675196D03*
Y667322D03*
Y659448D03*
Y651574D03*
X1105315Y690944D03*
Y683070D03*
Y675196D03*
Y667322D03*
Y659448D03*
Y651574D03*
X1123031Y718504D03*
Y710629D03*
Y702755D03*
X1097441Y718504D03*
Y710629D03*
Y702755D03*
X1115157Y714567D03*
Y706692D03*
Y698818D03*
X1105315Y714567D03*
Y706692D03*
Y698818D03*
G54D44*
X227063Y992475D03*
Y991975D03*
X293763Y580475D03*
Y579975D03*
X1867963Y993975D03*
Y993475D03*
G54D81*
G01X394744Y-485863D02*
X395618Y-484988D01*
X396273Y-483530D01*
X396710Y-481487D01*
X396273Y-479738D01*
X395400Y-478571D01*
X393871Y-477696D01*
X387976D01*
Y-495196D01*
X395181D01*
X396710Y-494030D01*
X397583Y-492279D01*
X398020Y-490238D01*
X397583Y-488196D01*
X396273Y-486446D01*
X394744Y-485863D01*
X387976D01*
G01X407441Y-495196D02*
Y-483530D01*
G01Y-485863D02*
X408533Y-484696D01*
X409625Y-483821D01*
X411153Y-483530D01*
X412244Y-483821D01*
X413555Y-484696D01*
G01X423413Y-500446D02*
X424723Y-501029D01*
X426470Y-500446D01*
X427561Y-499280D01*
X428435Y-497821D01*
X429744Y-493155D01*
X432583Y-483530D01*
G01X425596D02*
X429744Y-493155D01*
G01X448991Y-484988D02*
X447463Y-483821D01*
X446153Y-483530D01*
X444406Y-484113D01*
X443096Y-485279D01*
X442223Y-487321D01*
X442004Y-489363D01*
X442223Y-491405D01*
X443096Y-493155D01*
X444406Y-494613D01*
X446153Y-495196D01*
X447681Y-494613D01*
X448991Y-493446D01*
G01X459723Y-487321D02*
X466710D01*
X466055Y-485279D01*
X464963Y-484113D01*
X463435Y-483530D01*
X461906Y-483821D01*
X460596Y-484696D01*
X459723Y-486738D01*
X459286Y-488488D01*
Y-490238D01*
X459723Y-491988D01*
X460815Y-493738D01*
X462125Y-494904D01*
X463653Y-495196D01*
X465181Y-494613D01*
X466710Y-492863D01*
G01X502801Y-479155D02*
X501491Y-478279D01*
X499963Y-477696D01*
X498216D01*
X496251Y-478571D01*
X494723Y-480029D01*
X493631Y-481780D01*
X492758Y-484696D01*
X492539Y-487321D01*
X492976Y-489946D01*
X493631Y-491696D01*
X494941Y-493446D01*
X496470Y-494613D01*
X497998Y-495196D01*
X499526D01*
X501055Y-494613D01*
X502365Y-493738D01*
X503457Y-492572D01*
G01X519428Y-495196D02*
Y-483530D01*
G01Y-485571D02*
X518555Y-484405D01*
X517244Y-483821D01*
X515716Y-483530D01*
X514188Y-484113D01*
X512878Y-485279D01*
X512004Y-487029D01*
X511568Y-489363D01*
X512004Y-491696D01*
X512878Y-493446D01*
X514188Y-494613D01*
X515716Y-495196D01*
X517244Y-494904D01*
X518555Y-494030D01*
X519428Y-492863D01*
G01X529286Y-495196D02*
Y-483530D01*
G01Y-486446D02*
X530160Y-484988D01*
X531470Y-483821D01*
X533216Y-483530D01*
X534744Y-483821D01*
X536055Y-484988D01*
X536710Y-487029D01*
Y-495196D01*
G01X545913Y-500446D02*
X547223Y-501029D01*
X548970Y-500446D01*
X550061Y-499280D01*
X550935Y-497821D01*
X552244Y-493155D01*
X555083Y-483530D01*
G01X548096D02*
X552244Y-493155D01*
G01X567998Y-495196D02*
X566688Y-494904D01*
X565378Y-493738D01*
X564504Y-491696D01*
X564068Y-489363D01*
X564504Y-487029D01*
X565378Y-484988D01*
X566688Y-483821D01*
X567998Y-483530D01*
X569308Y-483821D01*
X570618Y-484988D01*
X571491Y-487029D01*
X571710Y-489363D01*
X571491Y-491696D01*
X570618Y-493738D01*
X569308Y-494904D01*
X567998Y-495196D01*
G01X581786D02*
Y-483530D01*
G01Y-486446D02*
X582660Y-484988D01*
X583970Y-483821D01*
X585716Y-483530D01*
X587244Y-483821D01*
X588555Y-484988D01*
X589210Y-487029D01*
Y-495196D01*
G01X616350D02*
Y-477696D01*
X624646D01*
G01X621590Y-486154D02*
X616350D01*
G01X637998Y-495779D02*
X637561Y-495488D01*
Y-494904D01*
X637998Y-494613D01*
X638435Y-494904D01*
Y-495488D01*
X637998Y-495779D01*
G01X650695Y-495196D02*
Y-477696D01*
X655061D01*
X656808Y-478571D01*
X658118Y-479738D01*
X659210Y-481487D01*
X660083Y-483530D01*
X660301Y-486446D01*
X660083Y-489363D01*
X659210Y-491405D01*
X658118Y-493155D01*
X656808Y-494321D01*
X655061Y-495196D01*
X650695D01*
G01X668631D02*
Y-477696D01*
X673871D01*
X675618Y-478571D01*
X676928Y-480613D01*
X677365Y-482946D01*
X676928Y-485279D01*
X675836Y-487029D01*
X673871Y-487905D01*
X668631D01*
G01X692244Y-485863D02*
X693118Y-484988D01*
X693773Y-483530D01*
X694210Y-481487D01*
X693773Y-479738D01*
X692900Y-478571D01*
X691371Y-477696D01*
X685476D01*
Y-495196D01*
X692681D01*
X694210Y-494030D01*
X695083Y-492279D01*
X695520Y-490238D01*
X695083Y-488196D01*
X693773Y-486446D01*
X692244Y-485863D01*
X685476D01*
G01X501071Y-450196D02*
Y-432696D01*
X506748Y-447279D01*
X512425Y-432696D01*
Y-450196D01*
G01X524248D02*
X522938Y-449904D01*
X521628Y-448738D01*
X520754Y-446696D01*
X520318Y-444363D01*
X520754Y-442029D01*
X521628Y-439988D01*
X522938Y-438821D01*
X524248Y-438530D01*
X525558Y-438821D01*
X526868Y-439988D01*
X527741Y-442029D01*
X527960Y-444363D01*
X527741Y-446696D01*
X526868Y-448738D01*
X525558Y-449904D01*
X524248Y-450196D01*
G01X545678Y-432696D02*
Y-450196D01*
G01Y-447572D02*
X544805Y-449030D01*
X543494Y-449904D01*
X541966Y-450196D01*
X540220Y-449613D01*
X538910Y-448155D01*
X538036Y-446405D01*
X537818Y-444363D01*
X538036Y-442321D01*
X538910Y-440571D01*
X540220Y-439113D01*
X541966Y-438530D01*
X543494Y-438821D01*
X544586Y-439405D01*
X545678Y-440571D01*
G01X555973Y-442321D02*
X562960D01*
X562305Y-440279D01*
X561213Y-439113D01*
X559685Y-438530D01*
X558156Y-438821D01*
X556846Y-439696D01*
X555973Y-441738D01*
X555536Y-443488D01*
Y-445238D01*
X555973Y-446988D01*
X557065Y-448738D01*
X558375Y-449904D01*
X559903Y-450196D01*
X561431Y-449613D01*
X562960Y-447863D01*
G01X576748Y-450196D02*
Y-432696D01*
G01X754448Y-495196D02*
Y-477696D01*
X751828Y-481196D01*
G01Y-495196D02*
X757068D01*
G01X767800Y-487905D02*
X769328Y-485863D01*
X770638Y-484696D01*
X772385Y-484113D01*
X773913Y-484696D01*
X775005Y-485863D01*
X775878Y-487613D01*
X776096Y-489654D01*
X775878Y-491405D01*
X775005Y-493155D01*
X773694Y-494613D01*
X772166Y-495196D01*
X770420Y-494613D01*
X768891Y-492863D01*
X768018Y-490238D01*
X767800Y-487321D01*
X768236Y-483530D01*
X768891Y-481487D01*
X769983Y-479446D01*
X771511Y-477988D01*
X773040Y-477696D01*
X774568Y-478279D01*
X775660Y-479738D01*
G01X784645Y-491696D02*
X785954Y-493738D01*
X787701Y-494904D01*
X789666Y-495196D01*
X791413Y-494904D01*
X793160Y-493446D01*
X794251Y-491696D01*
X794470Y-489946D01*
X794033Y-487905D01*
X792505Y-486446D01*
X790976Y-485863D01*
X789011D01*
G01X790976D02*
X792286Y-484988D01*
X793378Y-483530D01*
X793815Y-481780D01*
X793378Y-480029D01*
X792286Y-478571D01*
X790321Y-477696D01*
X788356Y-477988D01*
X786391Y-479155D01*
G01X806948Y-495196D02*
Y-477696D01*
X804328Y-481196D01*
G01Y-495196D02*
X809568D01*
G01X819645Y-492572D02*
X820954Y-494030D01*
X822483Y-494904D01*
X824448Y-495196D01*
X826413Y-494613D01*
X827941Y-493446D01*
X829033Y-491405D01*
X829251Y-489071D01*
X828815Y-486738D01*
X827723Y-485279D01*
X826194Y-484113D01*
X824666Y-483821D01*
X823138Y-484113D01*
X821173Y-485279D01*
X821828Y-477696D01*
X827723D01*
G01X741331Y-450196D02*
Y-432696D01*
X746571D01*
X748318Y-433571D01*
X749628Y-435613D01*
X750065Y-437946D01*
X749628Y-440279D01*
X748536Y-442029D01*
X746571Y-442905D01*
X741331D01*
G01X768001Y-434155D02*
X766691Y-433279D01*
X765163Y-432696D01*
X763416D01*
X761451Y-433571D01*
X759923Y-435029D01*
X758831Y-436780D01*
X757958Y-439696D01*
X757739Y-442321D01*
X758176Y-444946D01*
X758831Y-446696D01*
X760141Y-448446D01*
X761670Y-449613D01*
X763198Y-450196D01*
X764726D01*
X766255Y-449613D01*
X767565Y-448738D01*
X768657Y-447572D01*
G01X782444Y-440863D02*
X783318Y-439988D01*
X783973Y-438530D01*
X784410Y-436487D01*
X783973Y-434738D01*
X783100Y-433571D01*
X781571Y-432696D01*
X775676D01*
Y-450196D01*
X782881D01*
X784410Y-449030D01*
X785283Y-447279D01*
X785720Y-445238D01*
X785283Y-443196D01*
X783973Y-441446D01*
X782444Y-440863D01*
X775676D01*
G01X791648Y-456029D02*
X804748D01*
G01X810676Y-450196D02*
Y-432696D01*
X820720Y-450196D01*
Y-432696D01*
G01X833198Y-450196D02*
X831451Y-449904D01*
X829923Y-448738D01*
X828613Y-446988D01*
X827739Y-444946D01*
X827303Y-442613D01*
Y-440279D01*
X827739Y-437946D01*
X828613Y-435904D01*
X829923Y-434155D01*
X831451Y-432988D01*
X833198Y-432696D01*
X834944Y-432988D01*
X836473Y-434155D01*
X837783Y-435904D01*
X838657Y-437946D01*
X839093Y-440279D01*
Y-442613D01*
X838657Y-444946D01*
X837783Y-446988D01*
X836473Y-448738D01*
X834944Y-449904D01*
X833198Y-450196D01*
G01X884039Y-432696D02*
X889498Y-450196D01*
X894957Y-432696D01*
G01X911365Y-450196D02*
X902631D01*
Y-432696D01*
X911365D01*
G01X907871Y-441154D02*
X902631D01*
G01X920131Y-450196D02*
Y-432696D01*
X925590D01*
X927336Y-433571D01*
X928428Y-434738D01*
X928865Y-437071D01*
X928428Y-439405D01*
X927118Y-440863D01*
X925590Y-441738D01*
X920131D01*
G01X925590D02*
X928865Y-450196D01*
G01X941998Y-450779D02*
X941561Y-450488D01*
Y-449904D01*
X941998Y-449613D01*
X942435Y-449904D01*
Y-450488D01*
X941998Y-450779D01*
G01X915748Y-495196D02*
Y-477696D01*
X913128Y-481196D01*
G01Y-495196D02*
X918368D01*
G01X1082981Y-432696D02*
Y-450196D01*
X1091715D01*
G01X1108778D02*
Y-438530D01*
G01Y-440571D02*
X1107905Y-439405D01*
X1106594Y-438821D01*
X1105066Y-438530D01*
X1103538Y-439113D01*
X1102228Y-440279D01*
X1101354Y-442029D01*
X1100918Y-444363D01*
X1101354Y-446696D01*
X1102228Y-448446D01*
X1103538Y-449613D01*
X1105066Y-450196D01*
X1106594Y-449904D01*
X1107905Y-449030D01*
X1108778Y-447863D01*
G01X1117763Y-455446D02*
X1119073Y-456029D01*
X1120820Y-455446D01*
X1121911Y-454280D01*
X1122785Y-452821D01*
X1124094Y-448155D01*
X1126933Y-438530D01*
G01X1119946D02*
X1124094Y-448155D01*
G01X1136573Y-442321D02*
X1143560D01*
X1142905Y-440279D01*
X1141813Y-439113D01*
X1140285Y-438530D01*
X1138756Y-438821D01*
X1137446Y-439696D01*
X1136573Y-441738D01*
X1136136Y-443488D01*
Y-445238D01*
X1136573Y-446988D01*
X1137665Y-448738D01*
X1138975Y-449904D01*
X1140503Y-450196D01*
X1142031Y-449613D01*
X1143560Y-447863D01*
G01X1154291Y-450196D02*
Y-438530D01*
G01Y-440863D02*
X1155383Y-439696D01*
X1156475Y-438821D01*
X1158003Y-438530D01*
X1159094Y-438821D01*
X1160405Y-439696D01*
G01X1144215Y-477696D02*
Y-495196D01*
X1135481D01*
G01X1122348D02*
Y-477696D01*
X1124968Y-481196D01*
G01Y-495196D02*
X1119728D01*
G01X1108996Y-480613D02*
X1107686Y-478863D01*
X1106158Y-477988D01*
X1104411Y-477696D01*
X1102228Y-478279D01*
X1100700Y-479738D01*
X1100263Y-481487D01*
X1100481Y-483238D01*
X1101355Y-484696D01*
X1105721Y-487613D01*
X1107686Y-489654D01*
X1108996Y-492572D01*
X1109433Y-495196D01*
X1100263D01*
G01X1312898D02*
X1311151Y-494904D01*
X1309623Y-493738D01*
X1308313Y-491988D01*
X1307439Y-489946D01*
X1307003Y-487613D01*
Y-485279D01*
X1307439Y-482946D01*
X1308313Y-480904D01*
X1309623Y-479155D01*
X1311151Y-477988D01*
X1312898Y-477696D01*
X1314644Y-477988D01*
X1316173Y-479155D01*
X1317483Y-480904D01*
X1318357Y-482946D01*
X1318793Y-485279D01*
Y-487613D01*
X1318357Y-489946D01*
X1317483Y-491988D01*
X1316173Y-493738D01*
X1314644Y-494904D01*
X1312898Y-495196D01*
G01X1314644Y-490529D02*
X1317265Y-495196D01*
G01X1325595Y-477696D02*
Y-490238D01*
X1326468Y-492863D01*
X1328215Y-494613D01*
X1330398Y-495196D01*
X1332581Y-494613D01*
X1334328Y-492863D01*
X1335201Y-490238D01*
Y-477696D01*
G01X1345278D02*
X1350518D01*
G01X1347898D02*
Y-495196D01*
G01X1345278D02*
X1350518D01*
G01X1360376D02*
Y-477696D01*
X1370420Y-495196D01*
Y-477696D01*
G01X1387701Y-479155D02*
X1386391Y-478279D01*
X1384863Y-477696D01*
X1383116D01*
X1381151Y-478571D01*
X1379623Y-480029D01*
X1378531Y-481780D01*
X1377658Y-484696D01*
X1377439Y-487321D01*
X1377876Y-489946D01*
X1378531Y-491696D01*
X1379841Y-493446D01*
X1381370Y-494613D01*
X1382898Y-495196D01*
X1384426D01*
X1385955Y-494613D01*
X1387265Y-493738D01*
X1388357Y-492572D01*
G01X1400398Y-495196D02*
Y-487321D01*
X1396031Y-477696D01*
G01X1404765D02*
X1400398Y-487321D01*
G01X1290595Y-450196D02*
Y-432696D01*
X1294961D01*
X1296708Y-433571D01*
X1298018Y-434738D01*
X1299110Y-436487D01*
X1299983Y-438530D01*
X1300201Y-441446D01*
X1299983Y-444363D01*
X1299110Y-446405D01*
X1298018Y-448155D01*
X1296708Y-449321D01*
X1294961Y-450196D01*
X1290595D01*
G01X1309623Y-442321D02*
X1316610D01*
X1315955Y-440279D01*
X1314863Y-439113D01*
X1313335Y-438530D01*
X1311806Y-438821D01*
X1310496Y-439696D01*
X1309623Y-441738D01*
X1309186Y-443488D01*
Y-445238D01*
X1309623Y-446988D01*
X1310715Y-448738D01*
X1312025Y-449904D01*
X1313553Y-450196D01*
X1315081Y-449613D01*
X1316610Y-447863D01*
G01X1327123Y-448155D02*
X1328215Y-449321D01*
X1329743Y-450196D01*
X1331053D01*
X1332363Y-449613D01*
X1333236Y-448738D01*
X1333673Y-447572D01*
X1333455Y-445821D01*
X1332581Y-444946D01*
X1328651Y-443196D01*
X1327778Y-441154D01*
X1328215Y-439696D01*
X1329088Y-438821D01*
X1330398Y-438530D01*
X1331708Y-438821D01*
X1333018Y-439696D01*
G01X1347898Y-438530D02*
Y-450196D01*
G01Y-433863D02*
X1347461Y-433571D01*
Y-432988D01*
X1347898Y-432696D01*
X1348335Y-432988D01*
Y-433571D01*
X1347898Y-433863D01*
G01X1362341Y-454571D02*
X1363870Y-455738D01*
X1365616Y-456029D01*
X1367144Y-455738D01*
X1368455Y-454280D01*
X1369328Y-452238D01*
Y-438530D01*
G01Y-440863D02*
X1368455Y-439696D01*
X1367144Y-438821D01*
X1365616Y-438530D01*
X1363870Y-439113D01*
X1362778Y-440279D01*
X1361904Y-442321D01*
X1361468Y-444363D01*
X1361686Y-446113D01*
X1362560Y-448155D01*
X1363870Y-449613D01*
X1365616Y-450196D01*
X1366926Y-449904D01*
X1368455Y-448738D01*
X1369328Y-447572D01*
G01X1379186Y-450196D02*
Y-438530D01*
G01Y-441446D02*
X1380060Y-439988D01*
X1381370Y-438821D01*
X1383116Y-438530D01*
X1384644Y-438821D01*
X1385955Y-439988D01*
X1386610Y-442029D01*
Y-450196D01*
G01X1397123Y-442321D02*
X1404110D01*
X1403455Y-440279D01*
X1402363Y-439113D01*
X1400835Y-438530D01*
X1399306Y-438821D01*
X1397996Y-439696D01*
X1397123Y-441738D01*
X1396686Y-443488D01*
Y-445238D01*
X1397123Y-446988D01*
X1398215Y-448738D01*
X1399525Y-449904D01*
X1401053Y-450196D01*
X1402581Y-449613D01*
X1404110Y-447863D01*
G01X1414841Y-450196D02*
Y-438530D01*
G01Y-440863D02*
X1415933Y-439696D01*
X1417025Y-438821D01*
X1418553Y-438530D01*
X1419644Y-438821D01*
X1420955Y-439696D01*
G01X1461598Y-477696D02*
X1459851Y-478279D01*
X1458541Y-479738D01*
X1457668Y-481487D01*
X1457013Y-483821D01*
X1456795Y-486446D01*
X1457013Y-489071D01*
X1457668Y-491405D01*
X1458541Y-493155D01*
X1459851Y-494613D01*
X1461598Y-495196D01*
X1463344Y-494613D01*
X1464655Y-493155D01*
X1465528Y-491405D01*
X1466183Y-489071D01*
X1466401Y-486446D01*
X1466183Y-483821D01*
X1465528Y-481487D01*
X1464655Y-479738D01*
X1463344Y-478279D01*
X1461598Y-477696D01*
G01X1474950Y-487905D02*
X1476478Y-485863D01*
X1477788Y-484696D01*
X1479535Y-484113D01*
X1481063Y-484696D01*
X1482155Y-485863D01*
X1483028Y-487613D01*
X1483246Y-489654D01*
X1483028Y-491405D01*
X1482155Y-493155D01*
X1480844Y-494613D01*
X1479316Y-495196D01*
X1477570Y-494613D01*
X1476041Y-492863D01*
X1475168Y-490238D01*
X1474950Y-487321D01*
X1475386Y-483530D01*
X1476041Y-481487D01*
X1477133Y-479446D01*
X1478661Y-477988D01*
X1480190Y-477696D01*
X1481718Y-478279D01*
X1482810Y-479738D01*
G01X1492668Y-495779D02*
X1500528Y-477696D01*
G01X1514098D02*
X1512351Y-478279D01*
X1511041Y-479738D01*
X1510168Y-481487D01*
X1509513Y-483821D01*
X1509295Y-486446D01*
X1509513Y-489071D01*
X1510168Y-491405D01*
X1511041Y-493155D01*
X1512351Y-494613D01*
X1514098Y-495196D01*
X1515844Y-494613D01*
X1517155Y-493155D01*
X1518028Y-491405D01*
X1518683Y-489071D01*
X1518901Y-486446D01*
X1518683Y-483821D01*
X1518028Y-481487D01*
X1517155Y-479738D01*
X1515844Y-478279D01*
X1514098Y-477696D01*
G01X1527886Y-493155D02*
X1529415Y-494613D01*
X1531161Y-495196D01*
X1532908Y-494613D01*
X1534436Y-492863D01*
X1535528Y-490238D01*
X1535965Y-487613D01*
Y-484405D01*
X1535528Y-481780D01*
X1534436Y-479446D01*
X1533126Y-478279D01*
X1531598Y-477696D01*
X1529851Y-478279D01*
X1528541Y-479446D01*
X1527668Y-481196D01*
X1527231Y-483530D01*
X1527668Y-485571D01*
X1528760Y-487613D01*
X1530070Y-488780D01*
X1531598Y-489071D01*
X1533344Y-488488D01*
X1534655Y-487029D01*
X1535965Y-484405D01*
G01X1545168Y-495779D02*
X1553028Y-477696D01*
G01X1562450Y-480613D02*
X1563760Y-478863D01*
X1565288Y-477988D01*
X1567035Y-477696D01*
X1569218Y-478279D01*
X1570746Y-479738D01*
X1571183Y-481487D01*
X1570965Y-483238D01*
X1570091Y-484696D01*
X1565725Y-487613D01*
X1563760Y-489654D01*
X1562450Y-492572D01*
X1562013Y-495196D01*
X1571183D01*
G01X1584098Y-477696D02*
X1582351Y-478279D01*
X1581041Y-479738D01*
X1580168Y-481487D01*
X1579513Y-483821D01*
X1579295Y-486446D01*
X1579513Y-489071D01*
X1580168Y-491405D01*
X1581041Y-493155D01*
X1582351Y-494613D01*
X1584098Y-495196D01*
X1585844Y-494613D01*
X1587155Y-493155D01*
X1588028Y-491405D01*
X1588683Y-489071D01*
X1588901Y-486446D01*
X1588683Y-483821D01*
X1588028Y-481487D01*
X1587155Y-479738D01*
X1585844Y-478279D01*
X1584098Y-477696D01*
G01X1601598Y-495196D02*
Y-477696D01*
X1598978Y-481196D01*
G01Y-495196D02*
X1604218D01*
G01X1618661D02*
X1619098Y-491405D01*
X1619753Y-488196D01*
X1620626Y-485279D01*
X1621718Y-482071D01*
X1623465Y-477696D01*
X1614731D01*
G01X1509295Y-450196D02*
Y-432696D01*
X1513661D01*
X1515408Y-433571D01*
X1516718Y-434738D01*
X1517810Y-436487D01*
X1518683Y-438530D01*
X1518901Y-441446D01*
X1518683Y-444363D01*
X1517810Y-446405D01*
X1516718Y-448155D01*
X1515408Y-449321D01*
X1513661Y-450196D01*
X1509295D01*
G01X1535528D02*
Y-438530D01*
G01Y-440571D02*
X1534655Y-439405D01*
X1533344Y-438821D01*
X1531816Y-438530D01*
X1530288Y-439113D01*
X1528978Y-440279D01*
X1528104Y-442029D01*
X1527668Y-444363D01*
X1528104Y-446696D01*
X1528978Y-448446D01*
X1530288Y-449613D01*
X1531816Y-450196D01*
X1533344Y-449904D01*
X1534655Y-449030D01*
X1535528Y-447863D01*
G01X1549098Y-432696D02*
Y-450196D01*
G01X1546041Y-438530D02*
X1552155D01*
G01X1563323Y-442321D02*
X1570310D01*
X1569655Y-440279D01*
X1568563Y-439113D01*
X1567035Y-438530D01*
X1565506Y-438821D01*
X1564196Y-439696D01*
X1563323Y-441738D01*
X1562886Y-443488D01*
Y-445238D01*
X1563323Y-446988D01*
X1564415Y-448738D01*
X1565725Y-449904D01*
X1567253Y-450196D01*
X1568781Y-449613D01*
X1570310Y-447863D01*
G54D36*
X125600Y997700D03*
X192100Y585700D03*
X745983Y915989D03*
X852000Y458500D03*
X1426000Y558100D03*
Y562100D03*
X1767400Y1009700D03*
X1883050Y880323D03*
X1896800Y938000D03*
Y921000D03*
Y925000D03*
G54D27*
X93100Y974600D03*
X159800Y562600D03*
X741883Y868889D03*
X703883Y915489D03*
X707332Y943502D03*
X750968Y899898D03*
X961000Y1520500D03*
X1733218Y995429D03*
X1891877Y880603D03*
G54D54*
X736938Y887518D03*
Y889486D03*
X724826D03*
Y887518D03*
G54D72*
X986614Y1619764D03*
X974016D03*
Y1597126D03*
X986614D03*
X974016Y1591220D03*
Y1603031D03*
Y1613858D03*
X986614Y1591220D03*
Y1613858D03*
Y1603031D03*
X974016Y1642401D03*
X986614D03*
X974016Y1625669D03*
Y1636496D03*
Y1648307D03*
X986614Y1625669D03*
Y1636496D03*
Y1648307D03*
X1030709Y1619764D03*
X1014961D03*
X1002362D03*
Y1597126D03*
X1014961D03*
X1030709D03*
X1002362Y1591220D03*
Y1603031D03*
Y1613858D03*
X1014961Y1591220D03*
Y1603031D03*
Y1613858D03*
X1030709Y1591220D03*
Y1613858D03*
Y1603031D03*
X1002362Y1642401D03*
X1014961D03*
X1030709D03*
X1002362Y1625669D03*
Y1636496D03*
Y1648307D03*
X1014961Y1625669D03*
Y1636496D03*
Y1648307D03*
X1030709Y1625669D03*
Y1636496D03*
Y1648307D03*
X1043307Y1619764D03*
Y1597126D03*
Y1591220D03*
Y1603031D03*
Y1613858D03*
Y1642401D03*
Y1625669D03*
Y1636496D03*
Y1648307D03*
X1101457Y1588583D03*
X1119685D03*
X1101457Y1601181D03*
X1119685D03*
X1108150Y1588583D03*
X1126378D03*
X1108150Y1601181D03*
X1126378D03*
G54D45*
X429724Y63977D03*
Y68307D03*
X443898Y63977D03*
X458071D03*
X436811Y67914D03*
X450984D03*
X458071Y68307D03*
X443898D03*
X429724Y116339D03*
Y92323D03*
Y96654D03*
Y102166D03*
Y106496D03*
Y110827D03*
Y87993D03*
Y82481D03*
Y78150D03*
Y73819D03*
X443898Y116339D03*
X458071D03*
X436811Y114764D03*
X450984D03*
X436811Y82087D03*
X450984D03*
X443898Y92323D03*
X458071D03*
X443898Y96654D03*
X458071D03*
X436811Y96260D03*
X450984D03*
X443898Y102166D03*
X458071D03*
X436811Y100591D03*
X450984D03*
X443898Y106496D03*
X458071D03*
X436811Y106103D03*
X450984D03*
X443898Y110827D03*
X458071D03*
X436811Y110433D03*
X450984D03*
X458071Y87993D03*
Y82481D03*
X450984Y91930D03*
Y86418D03*
X443898Y87993D03*
Y82481D03*
X436811Y91930D03*
Y86418D03*
X443898Y78150D03*
X458071D03*
Y73819D03*
X450984Y77756D03*
Y72245D03*
X443898Y73819D03*
X436811Y77756D03*
Y72245D03*
X429724Y120670D03*
X443898D03*
X458071D03*
X436811Y120276D03*
X450984D03*
X465157Y67914D03*
X472244Y63977D03*
X479331Y67914D03*
X472244Y68307D03*
X465157Y114764D03*
X472244Y116339D03*
X479331Y114764D03*
X465157Y82087D03*
Y96260D03*
Y100591D03*
Y106103D03*
Y110433D03*
X479331Y82087D03*
X472244Y92323D03*
Y96654D03*
X479331Y96260D03*
X472244Y102166D03*
X479331Y100591D03*
X472244Y106496D03*
X479331Y106103D03*
X472244Y110827D03*
X479331Y110433D03*
Y91930D03*
Y86418D03*
X472244Y87993D03*
Y82481D03*
X465157Y91930D03*
Y86418D03*
X472244Y78150D03*
X479331Y77756D03*
Y72245D03*
X472244Y73819D03*
X465157Y77756D03*
Y72245D03*
Y120276D03*
X472244Y120670D03*
X479331Y120276D03*
X514764Y63977D03*
Y68307D03*
X550197Y67914D03*
X536024D03*
X521850D03*
X543110Y63977D03*
X528937D03*
X543110Y68307D03*
X528937D03*
X557283Y63977D03*
Y68307D03*
X514764Y116339D03*
Y110827D03*
Y106496D03*
Y102166D03*
Y96654D03*
Y92323D03*
Y87993D03*
Y82481D03*
Y78150D03*
Y73819D03*
X550197Y114764D03*
X536024D03*
X521850D03*
X543110Y116339D03*
X528937D03*
X550197Y110433D03*
X536024D03*
X521850D03*
X543110Y110827D03*
X528937D03*
X550197Y106103D03*
X536024D03*
X521850D03*
X543110Y106496D03*
X528937D03*
X550197Y100591D03*
X536024D03*
X521850D03*
X543110Y102166D03*
X528937D03*
X550197Y96260D03*
X536024D03*
X521850D03*
X543110Y96654D03*
X528937D03*
X543110Y92323D03*
X528937D03*
X550197Y82087D03*
X536024D03*
X521850D03*
X550197Y91930D03*
Y86418D03*
X543110Y87993D03*
Y82481D03*
X536024Y91930D03*
Y86418D03*
X528937Y87993D03*
Y82481D03*
X521850Y91930D03*
Y86418D03*
X543110Y78150D03*
X528937D03*
X550197Y77756D03*
Y72245D03*
X543110Y73819D03*
X536024Y77756D03*
Y72245D03*
X528937Y73819D03*
X521850Y77756D03*
Y72245D03*
X557283Y116339D03*
Y110827D03*
Y106496D03*
Y102166D03*
Y96654D03*
Y92323D03*
Y87993D03*
Y82481D03*
Y78150D03*
Y73819D03*
X514764Y120670D03*
X550197Y120276D03*
X536024D03*
X521850D03*
X543110Y120670D03*
X528937D03*
X557283D03*
X564370Y67914D03*
Y114764D03*
Y110433D03*
Y106103D03*
Y100591D03*
Y96260D03*
Y82087D03*
Y91930D03*
Y86418D03*
Y77756D03*
Y72245D03*
Y120276D03*
X833859Y1594095D03*
Y1598425D03*
Y1603937D03*
Y1608268D03*
Y1612599D03*
X840945Y1598032D03*
X826772D03*
X840945Y1602363D03*
X826772D03*
X840945Y1607874D03*
X826772D03*
X840945Y1612205D03*
X826772D03*
X840945Y1616536D03*
X826772D03*
X833859Y1618111D03*
Y1622441D03*
Y1626772D03*
Y1632284D03*
Y1636614D03*
Y1640945D03*
Y1646457D03*
Y1650788D03*
X840945Y1622048D03*
X826772D03*
X840945Y1626378D03*
X826772D03*
X840945Y1630709D03*
X826772D03*
X840945Y1636221D03*
X826772D03*
X840945Y1640551D03*
X826772D03*
X840945Y1644882D03*
X826772D03*
X840945Y1650394D03*
X826772D03*
X876378Y1594095D03*
X862205D03*
X848032D03*
X876378Y1598425D03*
X862205D03*
X848032D03*
X876378Y1603937D03*
X862205D03*
X848032D03*
X876378Y1608268D03*
X862205D03*
X848032D03*
X876378Y1612599D03*
X862205D03*
X848032D03*
X890552Y1598032D03*
X869292D03*
X855118D03*
X890552Y1602363D03*
X869292D03*
X855118D03*
X890552Y1607874D03*
X869292D03*
X855118D03*
X890552Y1612205D03*
X869292D03*
X855118D03*
X890552Y1616536D03*
X869292D03*
X855118D03*
X876378Y1618111D03*
X862205D03*
X848032D03*
X876378Y1622441D03*
X862205D03*
X848032D03*
X876378Y1626772D03*
X862205D03*
X848032D03*
X876378Y1632284D03*
X862205D03*
X848032D03*
X876378Y1636614D03*
X862205D03*
X848032D03*
X876378Y1640945D03*
X862205D03*
X848032D03*
X876378Y1646457D03*
X862205D03*
X848032D03*
X876378Y1650788D03*
X862205D03*
X848032D03*
X890552Y1622048D03*
X869292D03*
X855118D03*
X890552Y1626378D03*
X869292D03*
X855118D03*
X890552Y1630709D03*
X869292D03*
X855118D03*
X890552Y1636221D03*
X869292D03*
X855118D03*
X890552Y1640551D03*
X869292D03*
X855118D03*
X890552Y1644882D03*
X869292D03*
X855118D03*
X890552Y1650394D03*
X869292D03*
X855118D03*
X911811Y1603937D03*
Y1608268D03*
Y1612599D03*
X904725Y1602363D03*
Y1607874D03*
Y1612205D03*
Y1616536D03*
X911811Y1594095D03*
Y1598425D03*
X904725Y1598032D03*
X897638Y1594095D03*
Y1598425D03*
Y1603937D03*
Y1608268D03*
Y1612599D03*
X911811Y1632284D03*
Y1636614D03*
Y1640945D03*
Y1646457D03*
Y1650788D03*
X904725Y1630709D03*
Y1636221D03*
Y1640551D03*
Y1644882D03*
Y1650394D03*
X911811Y1618111D03*
Y1622441D03*
Y1626772D03*
X904725Y1622048D03*
Y1626378D03*
X897638Y1618111D03*
Y1622441D03*
Y1626772D03*
Y1632284D03*
Y1636614D03*
Y1640945D03*
Y1646457D03*
Y1650788D03*
X1091089Y988592D03*
X1095420D03*
X1100932D03*
X1105262D03*
X1109593D03*
X1115105D03*
X1119435D03*
X1123766D03*
X1129278D03*
X1133609D03*
X1095026Y995678D03*
X1099357D03*
X1104869D03*
X1109199D03*
X1113530D03*
X1119042D03*
X1123372D03*
X1127703D03*
X1133215D03*
X1091089Y1002765D03*
X1095420D03*
X1100932D03*
X1105262D03*
X1109593D03*
X1115105D03*
X1119435D03*
X1123766D03*
X1129278D03*
X1133609D03*
X1095026Y1009852D03*
X1099357D03*
X1104869D03*
X1109199D03*
X1113530D03*
X1119042D03*
X1123372D03*
X1127703D03*
X1133215D03*
X1091089Y1016938D03*
X1095420D03*
X1100932D03*
X1105262D03*
X1109593D03*
X1115105D03*
X1119435D03*
X1123766D03*
X1129278D03*
X1133609D03*
X1095026Y1024025D03*
X1099357D03*
X1104869D03*
X1109199D03*
X1113530D03*
X1119042D03*
X1123372D03*
X1127703D03*
X1133215D03*
X1091089Y1031111D03*
X1095420D03*
X1100932D03*
X1105262D03*
X1109593D03*
X1115105D03*
X1119435D03*
X1123766D03*
X1129278D03*
X1133609D03*
X1095026Y1038198D03*
X1099357D03*
X1104869D03*
X1109199D03*
X1113530D03*
X1119042D03*
X1123372D03*
X1127703D03*
X1133215D03*
X1091089Y1160257D03*
Y1174430D03*
X1095420Y1160257D03*
Y1174430D03*
X1100932Y1160257D03*
Y1174430D03*
X1105262Y1160257D03*
Y1174430D03*
X1109593Y1160257D03*
Y1174430D03*
X1115105Y1160257D03*
Y1174430D03*
X1119435Y1160257D03*
Y1174430D03*
X1123766Y1160257D03*
Y1174430D03*
X1129278Y1160257D03*
Y1174430D03*
X1133609Y1160257D03*
Y1174430D03*
X1095026Y1167343D03*
X1099357D03*
X1104869D03*
X1109199D03*
X1113530D03*
X1119042D03*
X1123372D03*
X1127703D03*
X1133215D03*
X1091089Y1188603D03*
Y1202776D03*
Y1216949D03*
X1095420Y1188603D03*
Y1202776D03*
Y1216949D03*
X1100932Y1188603D03*
Y1202776D03*
Y1216949D03*
X1105262Y1188603D03*
Y1202776D03*
Y1216949D03*
X1109593Y1188603D03*
Y1202776D03*
Y1216949D03*
X1115105Y1188603D03*
Y1202776D03*
Y1216949D03*
X1119435Y1188603D03*
Y1202776D03*
Y1216949D03*
X1123766Y1188603D03*
Y1202776D03*
Y1216949D03*
X1129278Y1188603D03*
Y1202776D03*
Y1216949D03*
X1133609Y1188603D03*
Y1202776D03*
Y1216949D03*
X1095026Y1181516D03*
Y1195690D03*
Y1209863D03*
Y1224036D03*
X1099357Y1181516D03*
Y1195690D03*
Y1209863D03*
Y1224036D03*
X1104869Y1181516D03*
Y1195690D03*
Y1209863D03*
Y1224036D03*
X1109199Y1181516D03*
Y1195690D03*
Y1209863D03*
Y1224036D03*
X1113530Y1181516D03*
Y1195690D03*
Y1209863D03*
Y1224036D03*
X1119042Y1181516D03*
Y1195690D03*
Y1209863D03*
Y1224036D03*
X1123372Y1181516D03*
Y1195690D03*
Y1209863D03*
Y1224036D03*
X1127703Y1181516D03*
Y1195690D03*
Y1209863D03*
Y1224036D03*
X1133215Y1181516D03*
Y1195690D03*
Y1209863D03*
Y1224036D03*
X1091089Y1231123D03*
Y1245296D03*
Y1259469D03*
Y1273642D03*
X1095420Y1231123D03*
Y1245296D03*
Y1259469D03*
Y1273642D03*
X1100932Y1231123D03*
Y1245296D03*
Y1259469D03*
Y1273642D03*
X1105262Y1231123D03*
Y1245296D03*
Y1259469D03*
Y1273642D03*
X1109593Y1231123D03*
Y1245296D03*
Y1259469D03*
Y1273642D03*
X1115105Y1231123D03*
Y1245296D03*
Y1259469D03*
Y1273642D03*
X1119435Y1231123D03*
Y1245296D03*
Y1259469D03*
Y1273642D03*
X1123766Y1231123D03*
Y1245296D03*
Y1259469D03*
Y1273642D03*
X1129278Y1231123D03*
Y1245296D03*
Y1259469D03*
Y1273642D03*
X1133609Y1231123D03*
Y1245296D03*
Y1259469D03*
Y1273642D03*
X1095026Y1238209D03*
Y1252382D03*
Y1266556D03*
X1099357Y1238209D03*
Y1252382D03*
Y1266556D03*
X1104869Y1238209D03*
Y1252382D03*
Y1266556D03*
X1109199Y1238209D03*
Y1252382D03*
Y1266556D03*
X1113530Y1238209D03*
Y1252382D03*
Y1266556D03*
X1119042Y1238209D03*
Y1252382D03*
Y1266556D03*
X1123372Y1238209D03*
Y1252382D03*
Y1266556D03*
X1127703Y1238209D03*
Y1252382D03*
Y1266556D03*
X1133215Y1238209D03*
Y1252382D03*
Y1266556D03*
X1091089Y1287816D03*
Y1301989D03*
Y1316162D03*
X1095420Y1287816D03*
Y1301989D03*
Y1316162D03*
X1100932Y1287816D03*
Y1301989D03*
Y1316162D03*
X1105262Y1287816D03*
Y1301989D03*
Y1316162D03*
X1109593Y1287816D03*
Y1301989D03*
Y1316162D03*
X1115105Y1287816D03*
Y1301989D03*
Y1316162D03*
X1119435Y1287816D03*
Y1301989D03*
Y1316162D03*
X1123766Y1287816D03*
Y1301989D03*
Y1316162D03*
X1129278Y1287816D03*
Y1301989D03*
Y1316162D03*
X1133609Y1287816D03*
Y1301989D03*
Y1316162D03*
X1095026Y1280729D03*
Y1294902D03*
Y1309075D03*
Y1323249D03*
X1099357Y1280729D03*
Y1294902D03*
Y1309075D03*
Y1323249D03*
X1104869Y1280729D03*
Y1294902D03*
Y1309075D03*
Y1323249D03*
X1109199Y1280729D03*
Y1294902D03*
Y1309075D03*
Y1323249D03*
X1113530Y1280729D03*
Y1294902D03*
Y1309075D03*
Y1323249D03*
X1119042Y1280729D03*
Y1294902D03*
Y1309075D03*
Y1323249D03*
X1123372Y1280729D03*
Y1294902D03*
Y1309075D03*
Y1323249D03*
X1127703Y1280729D03*
Y1294902D03*
Y1309075D03*
Y1323249D03*
X1133215Y1280729D03*
Y1294902D03*
Y1309075D03*
Y1323249D03*
X1091089Y1330335D03*
Y1344508D03*
Y1358682D03*
Y1372855D03*
X1095420Y1330335D03*
Y1344508D03*
Y1358682D03*
Y1372855D03*
X1100932Y1330335D03*
Y1344508D03*
Y1358682D03*
Y1372855D03*
X1105262Y1330335D03*
Y1344508D03*
Y1358682D03*
Y1372855D03*
X1109593Y1330335D03*
Y1344508D03*
Y1358682D03*
Y1372855D03*
X1115105Y1330335D03*
Y1344508D03*
Y1358682D03*
Y1372855D03*
X1119435Y1330335D03*
Y1344508D03*
Y1358682D03*
Y1372855D03*
X1123766Y1330335D03*
Y1344508D03*
Y1358682D03*
Y1372855D03*
X1129278Y1330335D03*
Y1344508D03*
Y1358682D03*
Y1372855D03*
X1133609Y1330335D03*
Y1344508D03*
Y1358682D03*
Y1372855D03*
X1095026Y1337422D03*
Y1351595D03*
Y1365768D03*
X1099357Y1337422D03*
Y1351595D03*
Y1365768D03*
X1104869Y1337422D03*
Y1351595D03*
Y1365768D03*
X1109199Y1337422D03*
Y1351595D03*
Y1365768D03*
X1113530Y1337422D03*
Y1351595D03*
Y1365768D03*
X1119042Y1337422D03*
Y1351595D03*
Y1365768D03*
X1123372Y1337422D03*
Y1351595D03*
Y1365768D03*
X1127703Y1337422D03*
Y1351595D03*
Y1365768D03*
X1133215Y1337422D03*
Y1351595D03*
Y1365768D03*
X1091089Y1387028D03*
Y1401201D03*
X1095420Y1387028D03*
Y1401201D03*
X1100932Y1387028D03*
Y1401201D03*
X1105262Y1387028D03*
Y1401201D03*
X1109593Y1387028D03*
Y1401201D03*
X1115105Y1387028D03*
Y1401201D03*
X1119435Y1387028D03*
Y1401201D03*
X1123766Y1387028D03*
Y1401201D03*
X1129278Y1387028D03*
Y1401201D03*
X1133609Y1387028D03*
Y1401201D03*
X1095026Y1379942D03*
Y1394115D03*
Y1408288D03*
X1099357Y1379942D03*
Y1394115D03*
Y1408288D03*
X1104869Y1379942D03*
Y1394115D03*
Y1408288D03*
X1109199Y1379942D03*
Y1394115D03*
Y1408288D03*
X1113530Y1379942D03*
Y1394115D03*
Y1408288D03*
X1119042Y1379942D03*
Y1394115D03*
Y1408288D03*
X1123372Y1379942D03*
Y1394115D03*
Y1408288D03*
X1127703Y1379942D03*
Y1394115D03*
Y1408288D03*
X1133215Y1379942D03*
Y1394115D03*
Y1408288D03*
X1398228Y63977D03*
Y68307D03*
X1412402Y63977D03*
X1426575D03*
X1405315Y67914D03*
X1419488D03*
X1426575Y68307D03*
X1412402D03*
X1398228Y116339D03*
Y92323D03*
Y96654D03*
Y102166D03*
Y106496D03*
Y110827D03*
Y87993D03*
Y82481D03*
Y78150D03*
Y73819D03*
X1412402Y116339D03*
X1426575D03*
X1405315Y114764D03*
X1419488D03*
X1405315Y82087D03*
X1419488D03*
X1412402Y92323D03*
X1426575D03*
X1412402Y96654D03*
X1426575D03*
X1405315Y96260D03*
X1419488D03*
X1412402Y102166D03*
X1426575D03*
X1405315Y100591D03*
X1419488D03*
X1412402Y106496D03*
X1426575D03*
X1405315Y106103D03*
X1419488D03*
X1412402Y110827D03*
X1426575D03*
X1405315Y110433D03*
X1419488D03*
X1426575Y87993D03*
Y82481D03*
X1419488Y91930D03*
Y86418D03*
X1412402Y87993D03*
Y82481D03*
X1405315Y91930D03*
Y86418D03*
X1412402Y78150D03*
X1426575D03*
Y73819D03*
X1419488Y77756D03*
Y72245D03*
X1412402Y73819D03*
X1405315Y77756D03*
Y72245D03*
X1398228Y120670D03*
X1412402D03*
X1426575D03*
X1405315Y120276D03*
X1419488D03*
X1433661Y67914D03*
X1440748Y63977D03*
X1447835Y67914D03*
X1440748Y68307D03*
X1433661Y114764D03*
X1440748Y116339D03*
X1447835Y114764D03*
X1433661Y82087D03*
Y96260D03*
Y100591D03*
Y106103D03*
Y110433D03*
X1447835Y82087D03*
X1440748Y92323D03*
Y96654D03*
X1447835Y96260D03*
X1440748Y102166D03*
X1447835Y100591D03*
X1440748Y106496D03*
X1447835Y106103D03*
X1440748Y110827D03*
X1447835Y110433D03*
Y91930D03*
Y86418D03*
X1440748Y87993D03*
Y82481D03*
X1433661Y91930D03*
Y86418D03*
X1440748Y78150D03*
X1447835Y77756D03*
Y72245D03*
X1440748Y73819D03*
X1433661Y77756D03*
Y72245D03*
Y120276D03*
X1440748Y120670D03*
X1447835Y120276D03*
X1483268Y63977D03*
Y68307D03*
X1518701Y67914D03*
X1504528D03*
X1490354D03*
X1511614Y63977D03*
X1497441D03*
X1511614Y68307D03*
X1497441D03*
X1483268Y116339D03*
Y110827D03*
Y106496D03*
Y102166D03*
Y96654D03*
Y92323D03*
Y87993D03*
Y82481D03*
Y78150D03*
Y73819D03*
X1518701Y114764D03*
X1504528D03*
X1490354D03*
X1511614Y116339D03*
X1497441D03*
X1518701Y110433D03*
X1504528D03*
X1490354D03*
X1511614Y110827D03*
X1497441D03*
X1518701Y106103D03*
X1504528D03*
X1490354D03*
X1511614Y106496D03*
X1497441D03*
X1518701Y100591D03*
X1504528D03*
X1490354D03*
X1511614Y102166D03*
X1497441D03*
X1518701Y96260D03*
X1504528D03*
X1490354D03*
X1511614Y96654D03*
X1497441D03*
X1511614Y92323D03*
X1497441D03*
X1518701Y82087D03*
X1504528D03*
X1490354D03*
X1518701Y91930D03*
Y86418D03*
X1511614Y87993D03*
Y82481D03*
X1504528Y91930D03*
Y86418D03*
X1497441Y87993D03*
Y82481D03*
X1490354Y91930D03*
Y86418D03*
X1511614Y78150D03*
X1497441D03*
X1518701Y77756D03*
Y72245D03*
X1511614Y73819D03*
X1504528Y77756D03*
Y72245D03*
X1497441Y73819D03*
X1490354Y77756D03*
Y72245D03*
X1483268Y120670D03*
X1518701Y120276D03*
X1504528D03*
X1490354D03*
X1511614Y120670D03*
X1497441D03*
X1532874Y67914D03*
X1525787Y63977D03*
Y68307D03*
X1532874Y114764D03*
X1525787Y116339D03*
X1532874Y110433D03*
X1525787Y110827D03*
X1532874Y106103D03*
X1525787Y106496D03*
X1532874Y100591D03*
X1525787Y102166D03*
X1532874Y96260D03*
X1525787Y96654D03*
Y92323D03*
X1532874Y82087D03*
Y91930D03*
Y86418D03*
X1525787Y87993D03*
Y82481D03*
Y78150D03*
X1532874Y77756D03*
Y72245D03*
X1525787Y73819D03*
X1532874Y120276D03*
X1525787Y120670D03*
G54D63*
X744633Y924689D03*
X744133D03*
X1858126Y800787D03*
X1858626D03*
G54D18*
X63463Y981525D03*
X129763Y554925D03*
X156941Y992844D03*
X223641Y580844D03*
X1702761Y1004047D03*
X1798741Y1004844D03*
G54D82*
G01X458071Y87993D02*
Y86467D01*
G02X457416Y85812I-655J0D01*
G01X456037D01*
G02X455103Y86746I0J934D01*
G01Y121614D01*
X458038Y135583D01*
X461924Y141484D01*
X476093Y163002D01*
X481407Y166519D01*
X499390Y196312D01*
X556801Y212886D01*
X686664Y239303D01*
X793230Y216978D01*
X795144Y217350D01*
X795719Y216963D01*
X797633Y217335D01*
X798020Y217910D01*
X799934Y218282D01*
X800509Y217895D01*
X802423Y218267D01*
X802810Y218841D01*
X804725Y219214D01*
X805299Y218826D01*
X807213Y219199D01*
X807601Y219773D01*
X809515Y220146D01*
X810089Y219758D01*
X812003Y220130D01*
X812391Y220705D01*
X835892Y225276D01*
X836467Y224889D01*
X838381Y225261D01*
X838768Y225836D01*
X840682Y226208D01*
X841257Y225820D01*
X843171Y226193D01*
X843558Y226767D01*
X845472Y227140D01*
X846047Y226752D01*
X847961Y227124D01*
X848349Y227699D01*
X850263Y228071D01*
X850837Y227684D01*
X852751Y228056D01*
X853139Y228631D01*
X884151Y234663D01*
X885710Y235834D01*
X886340Y235745D01*
X887899Y236916D01*
X887988Y237546D01*
X889547Y238718D01*
X890177Y238628D01*
X891736Y239800D01*
X891826Y240430D01*
X893385Y241601D01*
X894015Y241512D01*
X895574Y242683D01*
X895663Y243313D01*
X897222Y244485D01*
X897852Y244395D01*
X899411Y245567D01*
X899501Y246197D01*
X910157Y254204D01*
X910787Y254114D01*
X912346Y255286D01*
X912436Y255916D01*
X913995Y257087D01*
X914625Y256998D01*
X916184Y258169D01*
X916273Y258799D01*
X917832Y259971D01*
X918462Y259881D01*
X920021Y261053D01*
X920111Y261683D01*
X923184Y263992D01*
X930890D01*
G02X931613Y263691I-2J-1024D01*
G01X933795Y261509D01*
G02X933985Y261050I-459J-459D01*
G01Y260586D01*
G02X933795Y260127I-649J0D01*
G01X933157Y259489D01*
G02X932605Y259209I-706J708D01*
G01X932544Y259199D01*
G02X931932Y259297I-156J988D01*
G01X929331Y260630D01*
G01X458071Y82481D02*
Y84007D01*
G03X457416Y84662I-655J0D01*
G01X456037D01*
G02X453953Y86746I0J2084D01*
G01Y121734D01*
X456957Y136033D01*
X475261Y163832D01*
X480556Y167335D01*
X489414Y182010D01*
X498638Y197292D01*
X556526Y214004D01*
X686667Y240478D01*
X793238Y218152D01*
X883671Y235742D01*
X922800Y265142D01*
X930892D01*
G02X930897I2J-2175D01*
G02X932427Y264505I-8J-2175D01*
G01X934842Y262089D01*
G02X935135Y261382I-706J-707D01*
G01Y260254D01*
G02X934842Y259547I-999J0D01*
G01X934379Y259084D01*
X934380D01*
G03X934259Y258919I469J-471D01*
G03X934194Y258509I591J-304D01*
G03X934553Y258021I658J108D01*
G01X937205Y256693D01*
G01X450984Y91930D02*
Y90404D01*
G02X450329Y89749I-655J0D01*
G01X448950D01*
G02X448016Y90683I0J934D01*
G01Y122117D01*
X450990Y136284D01*
X498122Y207857D01*
X584283Y264889D01*
X648268Y277597D01*
X785866Y304924D01*
X786395Y304570D01*
X788308Y304950D01*
X788661Y305479D01*
X790574Y305859D01*
X791103Y305505D01*
X793016Y305885D01*
X793369Y306414D01*
X795282Y306794D01*
X795811Y306440D01*
X797724Y306820D01*
X798077Y307349D01*
X799990Y307729D01*
X801894Y307307D01*
X802266Y306722D01*
X804170Y306299D01*
X804754Y306672D01*
X806658Y306249D01*
X807030Y305665D01*
X808934Y305242D01*
X809518Y305614D01*
X811422Y305192D01*
X811794Y304607D01*
X813698Y304185D01*
X814282Y304557D01*
X816186Y304135D01*
X816558Y303550D01*
X818462Y303128D01*
X819046Y303500D01*
X837939Y299307D01*
X838281Y298771D01*
X840185Y298348D01*
X840722Y298690D01*
X842625Y298267D01*
X842967Y297731D01*
X844871Y297308D01*
X845408Y297650D01*
X847311Y297227D01*
X847653Y296691D01*
X849557Y296268D01*
X850094Y296610D01*
X874299Y291238D01*
X874671Y290654D01*
X876575Y290231D01*
X877159Y290603D01*
X879063Y290181D01*
X879435Y289596D01*
X881339Y289174D01*
X881923Y289546D01*
X883827Y289124D01*
X884199Y288539D01*
X886103Y288117D01*
X886687Y288489D01*
X903374Y284785D01*
X903716Y284249D01*
X905619Y283826D01*
X906156Y284168D01*
X908060Y283745D01*
X908402Y283209D01*
X910305Y282786D01*
X910842Y283128D01*
X926108Y279740D01*
X930430D01*
G02X931937Y279115I0J-2130D01*
G01X933795Y277257D01*
G02X933985Y276798I-459J-459D01*
G01Y276334D01*
G02X933795Y275875I-649J0D01*
G01X933157Y275237D01*
G02X932605Y274957I-706J708D01*
G01X932544Y274947D01*
G02X931932Y275045I-156J988D01*
G01X929331Y276378D01*
G01X450984Y86418D02*
Y87944D01*
G03X450329Y88599I-655J0D01*
G01X448950D01*
G02X446866Y90683I0J2084D01*
G01Y122237D01*
X449909Y136734D01*
X497290Y208687D01*
X583837Y265973D01*
X648044Y278725D01*
X800003Y308905D01*
X926235Y280890D01*
X930431D01*
G02X932751Y279929I0J-3281D01*
G01X934842Y277837D01*
G02X935135Y277130I-706J-707D01*
G01Y276002D01*
G02X934842Y275295I-999J0D01*
G01X934379Y274832D01*
X934380D01*
G03X934259Y274667I469J-471D01*
G03X934194Y274257I591J-304D01*
G03X934553Y273769I658J108D01*
G01X937205Y272441D01*
G01X443898Y87993D02*
Y86467D01*
G02X443243Y85812I-655J0D01*
G01X441864D01*
G02X440930Y86746I0J934D01*
G01Y121614D01*
X444411Y138189D01*
X491572Y209687D01*
X493328Y212349D01*
X595589Y280523D01*
X745956Y310388D01*
X746532Y310003D01*
X748445Y310383D01*
X748830Y310959D01*
X750743Y311339D01*
X751319Y310954D01*
X753231Y311334D01*
X753617Y311910D01*
X755529Y312290D01*
X756105Y311905D01*
X758018Y312285D01*
X758403Y312861D01*
X768896Y314945D01*
X769472Y314560D01*
X771385Y314940D01*
X771770Y315516D01*
X773683Y315896D01*
X774259Y315511D01*
X776171Y315891D01*
X776557Y316467D01*
X778469Y316846D01*
X779045Y316461D01*
X780958Y316841D01*
X781343Y317417D01*
X789227Y318983D01*
X791149Y318651D01*
X791515Y318131D01*
X793437Y317800D01*
X793957Y318166D01*
X795879Y317835D01*
X796245Y317315D01*
X798167Y316983D01*
X798687Y317350D01*
X800609Y317018D01*
X800976Y316498D01*
X802897Y316166D01*
X803417Y316533D01*
X816381Y314295D01*
X816748Y313775D01*
X818670Y313443D01*
X819190Y313810D01*
X821111Y313478D01*
X821478Y312958D01*
X823400Y312626D01*
X823920Y312993D01*
X825841Y312662D01*
X826208Y312142D01*
X828130Y311810D01*
X828650Y312177D01*
X844701Y309406D01*
X845068Y308886D01*
X846990Y308554D01*
X847510Y308921D01*
X849431Y308589D01*
X849798Y308069D01*
X851720Y307738D01*
X852240Y308104D01*
X854161Y307773D01*
X854528Y307253D01*
X856450Y306921D01*
X856970Y307288D01*
X925319Y295488D01*
X930430D01*
G02X931937Y294863I0J-2130D01*
G01X933795Y293005D01*
G02X933985Y292546I-459J-459D01*
G01Y292082D01*
G02X933795Y291623I-649J0D01*
G01X933157Y290985D01*
G02X932605Y290705I-706J708D01*
G01X932544Y290695D01*
G02X931932Y290793I-156J988D01*
G01X929331Y292126D01*
G01X443898Y82481D02*
Y84007D01*
G03X443243Y84662I-655J0D01*
G01X441864D01*
G02X439780Y86746I0J2084D01*
G01Y121734D01*
X443330Y138640D01*
X490612Y210321D01*
X492496Y213177D01*
X595141Y281607D01*
X789212Y320153D01*
X925418Y296638D01*
X930431D01*
G02X932751Y295677I0J-3281D01*
G01X934842Y293585D01*
G02X935135Y292878I-706J-707D01*
G01Y291750D01*
G02X934842Y291043I-999J0D01*
G01X934379Y290580D01*
X934380D01*
G03X934259Y290415I469J-471D01*
G03X934194Y290005I591J-304D01*
G03X934553Y289517I658J108D01*
G01X937205Y288189D01*
G01X436811Y91930D02*
Y90404D01*
G02X436156Y89749I-655J0D01*
G01X434777D01*
G02X433843Y90683I0J934D01*
G01Y124347D01*
X437399Y141293D01*
X486944Y216149D01*
X593111Y286421D01*
X802404Y327990D01*
X804337Y327731D01*
X804757Y327180D01*
X806690Y326921D01*
X807241Y327342D01*
X809173Y327083D01*
X809594Y326532D01*
X811527Y326273D01*
X812077Y326693D01*
X814010Y326434D01*
X814431Y325884D01*
X816363Y325625D01*
X816914Y326045D01*
X837629Y323269D01*
X838050Y322718D01*
X839983Y322459D01*
X840533Y322880D01*
X842466Y322621D01*
X842887Y322070D01*
X844819Y321811D01*
X845370Y322232D01*
X847303Y321973D01*
X847723Y321422D01*
X849656Y321163D01*
X850207Y321584D01*
X852140Y321325D01*
X852560Y320774D01*
X854493Y320515D01*
X855044Y320936D01*
X871481Y318733D01*
X871867Y318227D01*
X873800Y317968D01*
X874306Y318355D01*
X876239Y318096D01*
X876625Y317590D01*
X878558Y317331D01*
X879063Y317717D01*
X880996Y317458D01*
X881382Y316952D01*
X883315Y316693D01*
X883821Y317080D01*
X885753Y316821D01*
X886140Y316315D01*
X888072Y316056D01*
X888578Y316442D01*
X908401Y313786D01*
X908787Y313280D01*
X910720Y313021D01*
X911226Y313407D01*
X913159Y313148D01*
X913545Y312643D01*
X915478Y312384D01*
X915983Y312770D01*
X917916Y312511D01*
X918302Y312005D01*
X920235Y311746D01*
X920741Y312132D01*
X922674Y311873D01*
X923060Y311368D01*
X924992Y311109D01*
X925498Y311495D01*
X927431Y311236D01*
X930430D01*
G02X931937Y310611I0J-2130D01*
G01X933795Y308753D01*
G02X933985Y308294I-459J-459D01*
G01Y307830D01*
G02X933795Y307371I-649J0D01*
G01X933157Y306733D01*
G02X932605Y306453I-706J708D01*
G01X932544Y306443D01*
G02X931932Y306541I-156J988D01*
G01X929331Y307874D01*
G01X436811Y86418D02*
Y87944D01*
G03X436156Y88599I-655J0D01*
G01X434777D01*
G02X432693Y90683I0J2084D01*
G01Y124467D01*
X436318Y141745D01*
X486114Y216979D01*
X592665Y287505D01*
X802367Y329156D01*
X927508Y312386D01*
X930431D01*
G02X932751Y311425I0J-3281D01*
G01X934842Y309333D01*
G02X935135Y308626I-706J-707D01*
G01Y307498D01*
G02X934842Y306791I-999J0D01*
G01X934379Y306328D01*
X934380D01*
G03X934259Y306163I469J-471D01*
G03X934194Y305753I591J-304D01*
G03X934553Y305265I658J108D01*
G01X937205Y303937D01*
G01X429724Y87993D02*
Y86467D01*
G02X429069Y85812I-655J0D01*
G01X427690D01*
G02X425600Y87902I0J2090D01*
G01Y118635D01*
X430549Y142229D01*
X486407Y226616D01*
X532463Y257055D01*
X533086Y256928D01*
X534713Y258003D01*
X534840Y258627D01*
X536467Y259702D01*
X537091Y259575D01*
X538718Y260650D01*
X538845Y261274D01*
X540472Y262349D01*
X541095Y262222D01*
X542722Y263297D01*
X542850Y263920D01*
X544476Y264996D01*
X545100Y264868D01*
X546727Y265944D01*
X546854Y266567D01*
X548481Y267642D01*
X549104Y267515D01*
X550731Y268590D01*
X550858Y269214D01*
X583561Y290828D01*
X801562Y335182D01*
X802140Y334800D01*
X804051Y335188D01*
X804433Y335766D01*
X806344Y336155D01*
X806922Y335773D01*
X808833Y336161D01*
X809215Y336739D01*
X811126Y337128D01*
Y337127D01*
X844625Y334159D01*
X845069Y333628D01*
X847012Y333456D01*
X847543Y333900D01*
X849485Y333728D01*
X849930Y333197D01*
X851873Y333025D01*
X852404Y333470D01*
X854346Y333298D01*
X854791Y332766D01*
X856734Y332594D01*
X857265Y333039D01*
X859207Y332867D01*
X859652Y332336D01*
X861595Y332164D01*
X862126Y332608D01*
X887278Y330380D01*
X887686Y329892D01*
X889629Y329720D01*
X890116Y330128D01*
X892059Y329956D01*
X892467Y329468D01*
X894410Y329296D01*
X894898Y329705D01*
X896840Y329533D01*
X897249Y329045D01*
X899191Y328872D01*
X899679Y329281D01*
X901621Y329109D01*
X902030Y328621D01*
X903972Y328449D01*
X904460Y328857D01*
X925608Y326984D01*
X930430D01*
G02X931937Y326359I0J-2130D01*
G01X933795Y324501D01*
G02X933985Y324042I-459J-459D01*
G01Y323578D01*
G02X933795Y323119I-649J0D01*
G01X933157Y322481D01*
G02X932605Y322201I-706J708D01*
G01X932544Y322191D01*
G02X931932Y322289I-156J988D01*
G01X929331Y323622D01*
G01X429724Y82481D02*
Y84007D01*
G03X429069Y84662I-655J0D01*
G01X427690D01*
G02X424450Y87902I0J3240D01*
G01Y118755D01*
X429468Y142681D01*
Y142680D01*
X485577Y227446D01*
X583113Y291911D01*
X811061Y338289D01*
X925659Y328134D01*
X930431D01*
G02X932751Y327173I0J-3281D01*
G01X934842Y325081D01*
G02X935135Y324374I-706J-707D01*
G01Y323246D01*
G02X934842Y322539I-999J0D01*
G01X934379Y322076D01*
X934380D01*
G03X934259Y321911I469J-471D01*
G03X934194Y321501I591J-304D01*
G03X934553Y321013I658J108D01*
G01X937205Y319685D01*
G01X479331Y91930D02*
Y90404D01*
G02X478676Y89749I-655J0D01*
G01X477297D01*
G02X476363Y90683I0J934D01*
G01Y125243D01*
X483153Y135545D01*
X535501Y170844D01*
X581884Y179859D01*
X597911Y190671D01*
X695096Y210441D01*
X778358Y193503D01*
X778740Y192925D01*
X780651Y192537D01*
X781229Y192919D01*
X783140Y192531D01*
X783522Y191953D01*
X785433Y191564D01*
X786011Y191947D01*
X795364Y190044D01*
X798322Y190638D01*
X798899Y190254D01*
X800811Y190638D01*
X801195Y191215D01*
X803107Y191599D01*
X803684Y191215D01*
X805595Y191599D01*
X805979Y192176D01*
X807891Y192559D01*
X808468Y192176D01*
X810380Y192559D01*
X810764Y193136D01*
X836479Y198300D01*
X837009Y197947D01*
X838921Y198331D01*
X839273Y198861D01*
X841185Y199245D01*
X841715Y198892D01*
X843627Y199276D01*
X843979Y199806D01*
X845891Y200190D01*
X846421Y199837D01*
X848333Y200221D01*
X848685Y200751D01*
X850597Y201135D01*
X851127Y200782D01*
X853039Y201166D01*
X853391Y201696D01*
X869244Y204879D01*
X873001Y205634D01*
X873530Y205281D01*
X875442Y205665D01*
X875794Y206194D01*
X877707Y206579D01*
X878236Y206226D01*
X880148Y206610D01*
X880500Y207139D01*
X882413Y207524D01*
X882942Y207171D01*
X884854Y207555D01*
X885206Y208084D01*
X887119Y208469D01*
X887648Y208116D01*
X889560Y208500D01*
X889912Y209029D01*
X909522Y212967D01*
X910051Y212615D01*
X911962Y212999D01*
X912315Y213528D01*
X914228Y213912D01*
X914757Y213560D01*
X916668Y213944D01*
X917021Y214473D01*
X922707Y215616D01*
X924702Y216592D01*
X930807D01*
G02X931937Y216123I-2J-1601D01*
G01X933795Y214265D01*
G02X933985Y213806I-459J-459D01*
G01Y213342D01*
G02X933795Y212883I-649J0D01*
G01X933157Y212245D01*
G02X932605Y211965I-706J708D01*
G01X932544Y211955D01*
G02X931932Y212053I-156J988D01*
G01X929331Y213386D01*
G01X479331Y86418D02*
Y87944D01*
G03X478676Y88599I-655J0D01*
G01X477297D01*
G02X475213Y90683I0J2084D01*
G01Y125686D01*
X475402Y125875D01*
X482319Y136370D01*
X535052Y171929D01*
X581434Y180944D01*
X597457Y191753D01*
X695096Y211615D01*
X795365Y191218D01*
X922335Y216715D01*
X924435Y217742D01*
X930806D01*
G02X932751Y216937I0J-2752D01*
G01X934842Y214845D01*
G02X935135Y214138I-706J-707D01*
G01Y213010D01*
G02X934842Y212303I-999J0D01*
G01X934379Y211840D01*
X934380D01*
G03X934259Y211675I469J-471D01*
G03X934194Y211265I591J-304D01*
G03X934553Y210777I658J108D01*
G01X937205Y209449D01*
G01X472244Y87993D02*
Y86467D01*
G02X471589Y85812I-655J0D01*
G01X470210D01*
G02X469276Y86746I0J934D01*
G01Y125818D01*
X474411Y133615D01*
Y133616D01*
X479546Y141414D01*
X505942Y159218D01*
X505941D01*
X532336Y177021D01*
X577178Y186145D01*
X593423Y196900D01*
X620214Y202324D01*
X620792Y201941D01*
X622703Y202328D01*
X623086Y202906D01*
X624997Y203293D01*
X625575Y202910D01*
X627486Y203297D01*
X627869Y203874D01*
X629780Y204261D01*
X630358Y203878D01*
X632269Y204265D01*
X632652Y204843D01*
X694606Y217386D01*
X780173Y199507D01*
X807966Y205028D01*
X808542Y204643D01*
X810455Y205023D01*
X810840Y205599D01*
X812753Y205979D01*
X813329Y205594D01*
X815241Y205974D01*
X815626Y206550D01*
X817539Y206930D01*
X818115Y206545D01*
X820028Y206925D01*
X820413Y207501D01*
X822326Y207881D01*
X822902Y207496D01*
X824814Y207876D01*
X825199Y208452D01*
X846145Y212613D01*
X846674Y212259D01*
X848587Y212639D01*
X848941Y213168D01*
X850853Y213548D01*
X851382Y213194D01*
X853295Y213574D01*
X853649Y214103D01*
X855561Y214483D01*
X856090Y214130D01*
X858003Y214510D01*
X858357Y215039D01*
X860269Y215419D01*
X860798Y215065D01*
X862711Y215445D01*
X863065Y215974D01*
X897850Y222885D01*
X898379Y222531D01*
X900292Y222911D01*
X900645Y223440D01*
X902558Y223820D01*
X903087Y223466D01*
X905000Y223846D01*
X905353Y224375D01*
X907266Y224755D01*
X907795Y224402D01*
X909708Y224782D01*
X910061Y225311D01*
X911974Y225691D01*
X912503Y225337D01*
X914416Y225717D01*
X914769Y226246D01*
X916682Y226626D01*
X924099Y232340D01*
X930805D01*
G02X931937Y231871I0J-1601D01*
G01X933795Y230013D01*
G02X933985Y229554I-459J-459D01*
G01Y229090D01*
G02X933795Y228631I-649J0D01*
G01X933157Y227993D01*
G02X932605Y227713I-706J708D01*
G01X932544Y227703D01*
G02X931932Y227801I-156J988D01*
G01X929331Y229134D01*
G01X472244Y82481D02*
Y84007D01*
G03X471589Y84662I-655J0D01*
G01X470210D01*
G02X468126Y86746I0J2084D01*
G01Y126163D01*
X478712Y142239D01*
X531882Y178103D01*
X574497Y186774D01*
X576729Y187228D01*
X592975Y197983D01*
X694610Y218561D01*
X780179Y200681D01*
X916193Y227702D01*
X923707Y233490D01*
X930806D01*
G02X932751Y232685I0J-2752D01*
G01X934842Y230593D01*
G02X935135Y229886I-706J-707D01*
G01Y228758D01*
G02X934842Y228051I-999J0D01*
G01X934379Y227588D01*
X934380D01*
G03X934259Y227423I469J-471D01*
G03X934194Y227013I591J-304D01*
G03X934553Y226525I658J108D01*
G01X937205Y225197D01*
G01X465157Y91930D02*
Y90404D01*
G02X464502Y89749I-655J0D01*
G01X463123D01*
G02X462189Y90683I0J934D01*
G01Y122105D01*
X464797Y134523D01*
X479899Y157439D01*
X550126Y204332D01*
X691554Y231828D01*
X777006Y213931D01*
X777385Y213351D01*
X779293Y212952D01*
X779873Y213331D01*
X781782Y212931D01*
X782161Y212351D01*
X784070Y211951D01*
X784650Y212330D01*
X786558Y211931D01*
X786937Y211351D01*
X788846Y210951D01*
X789426Y211330D01*
X796111Y209930D01*
X802173Y211136D01*
X802749Y210751D01*
X804661Y211132D01*
X805046Y211708D01*
X806959Y212089D01*
X807535Y211704D01*
X809447Y212084D01*
X809832Y212661D01*
X811745Y213041D01*
X812321Y212656D01*
X814234Y213037D01*
X814619Y213613D01*
X816531Y213994D01*
X817107Y213609D01*
X819020Y213989D01*
X819405Y214566D01*
X848715Y220398D01*
X849244Y220045D01*
X851156Y220425D01*
X851510Y220955D01*
X853422Y221335D01*
X853952Y220982D01*
X855864Y221362D01*
X856218Y221892D01*
X858130Y222272D01*
X858659Y221919D01*
X860572Y222299D01*
X860925Y222829D01*
X862838Y223209D01*
X863367Y222856D01*
X865280Y223236D01*
X865633Y223765D01*
X885248Y227669D01*
X885777Y227316D01*
X887690Y227696D01*
X888043Y228226D01*
X889956Y228606D01*
X890485Y228253D01*
X892398Y228633D01*
X892751Y229163D01*
X894664Y229543D01*
X895193Y229190D01*
X897105Y229570D01*
X897459Y230099D01*
X899371Y230480D01*
X899901Y230127D01*
X901813Y230507D01*
X902167Y231036D01*
X904033Y231408D01*
X925686Y248088D01*
X930806D01*
G02X931937Y247619I-1J-1601D01*
G01X932865Y246690D01*
X933794Y245761D01*
X933795D01*
G02X933985Y245302I-459J-459D01*
G01Y244838D01*
G02X933795Y244379I-649J0D01*
G01X933157Y243741D01*
G02X932605Y243461I-706J708D01*
G01X932544Y243451D01*
G02X931932Y243549I-156J988D01*
G01X929331Y244882D01*
G01X465157Y86418D02*
Y87944D01*
G03X464502Y88599I-655J0D01*
G01X463123D01*
G02X461039Y90683I0J2084D01*
G01Y122225D01*
X463716Y134973D01*
X471388Y146615D01*
X479066Y158267D01*
X549680Y205417D01*
X691562Y233002D01*
X796117Y211104D01*
X903544Y232484D01*
X925294Y249238D01*
X930806D01*
G02X932751Y248433I0J-2752D01*
G01X934842Y246341D01*
G02X935135Y245634I-706J-707D01*
G01Y244506D01*
G02X934842Y243799I-999J0D01*
G01X934379Y243336D01*
X934380D01*
G03X934259Y243171I469J-471D01*
G03X934194Y242761I591J-304D01*
G03X934553Y242273I658J108D01*
G01X937205Y240945D01*
G01X550197Y91930D02*
Y90404D01*
G03X550852Y89749I655J0D01*
G01X552231D01*
G03X553165Y90683I0J934D01*
G01Y123479D01*
X559174Y132603D01*
X562623Y134928D01*
X598628Y141927D01*
X826157Y97701D01*
X917921Y115536D01*
X930724D01*
X934661Y119473D01*
X948440D01*
X952377Y123410D01*
X956460D01*
X959075Y125047D01*
X961688Y126684D01*
X967208Y134867D01*
X987112Y237258D01*
X967489Y338205D01*
X960312Y348847D01*
X915117Y385193D01*
X904531Y400897D01*
X873378Y561153D01*
X885567Y623867D01*
X912316Y663526D01*
X912194Y664151D01*
X913285Y665768D01*
X913909Y665889D01*
X915000Y667506D01*
X914878Y668131D01*
X915969Y669747D01*
X916593Y669869D01*
X917684Y671485D01*
X917562Y672110D01*
X918653Y673727D01*
X919277Y673848D01*
X920368Y675465D01*
X920246Y676089D01*
X921337Y677706D01*
X921961Y677828D01*
X924559Y681679D01*
X927251Y683752D01*
X930663Y683763D01*
G03X931408Y683955I-2J1551D01*
G03X931758Y684218I-747J1358D01*
G01X932156Y684616D01*
G03X932342Y685191I-470J470D01*
G03X931983Y685679I-658J-108D01*
G01X929331Y687007D01*
G01X550197Y86418D02*
Y87944D01*
G02X550852Y88599I655J0D01*
G01X552231D01*
G03X554315Y90683I0J2084D01*
G01Y123134D01*
X560008Y131778D01*
X563072Y133843D01*
X598628Y140755D01*
X826157Y96529D01*
X918032Y114386D01*
X931201D01*
X935138Y118323D01*
X948917D01*
X952854Y122260D01*
X956791D01*
X962506Y125838D01*
X968293Y134417D01*
X988284Y237258D01*
X968574Y338654D01*
X961169Y349635D01*
X915974Y385981D01*
X905616Y401346D01*
X874550Y561153D01*
X886652Y623418D01*
X925409Y680881D01*
X927643Y682602D01*
X930662Y682613D01*
G03X931962Y682946I1J2701D01*
G03X932572Y683404I-1301J2367D01*
G01X933379Y684211D01*
G02X933931Y684491I706J-708D01*
G01X933992Y684501D01*
G02X934604Y684403I156J-988D01*
G01X937205Y683070D01*
G01X543110Y87993D02*
Y86467D01*
G03X543765Y85812I655J0D01*
G01X545144D01*
G03X546078Y86746I0J934D01*
G01Y91727D01*
X546079D01*
Y124303D01*
G02X546244Y124853I999J0D01*
G01X554025Y136670D01*
X558537Y139715D01*
X563051Y142762D01*
X595871Y149142D01*
X824416Y104717D01*
X920590Y123410D01*
X930724D01*
X934661Y127347D01*
X948441D01*
X952378Y131284D01*
X957022D01*
X961366Y137724D01*
Y137725D01*
X979677Y231927D01*
X958709Y339872D01*
X955312Y344907D01*
X910411Y381015D01*
X897265Y400511D01*
X866472Y558918D01*
X880890Y633107D01*
X911739Y678847D01*
X911618Y679472D01*
X912708Y681088D01*
X913333Y681210D01*
X914423Y682826D01*
X914302Y683451D01*
X915392Y685068D01*
X916017Y685189D01*
X917107Y686806D01*
X916986Y687431D01*
X918076Y689047D01*
X918701Y689169D01*
X919791Y690785D01*
X919669Y691410D01*
X920760Y693027D01*
X921385Y693148D01*
X923958Y696964D01*
X927251Y699500D01*
X930658Y699511D01*
X930663D01*
G03X931408Y699703I-2J1551D01*
G03X931758Y699966I-747J1358D01*
G01X932156Y700364D01*
G03X932342Y700939I-470J470D01*
G03X931983Y701427I-658J-108D01*
G01X929331Y702755D01*
G01X543110Y82481D02*
Y84007D01*
G02X543765Y84662I655J0D01*
G01X545144D01*
G03X547228Y86746I0J2084D01*
G01Y90577D01*
X547229D01*
Y124062D01*
G02X547336Y124420I650J1D01*
G01X554787Y135736D01*
G02X554967Y135918I543J-357D01*
G01X559181Y138761D01*
X561341Y140220D01*
X563501Y141677D01*
X595871Y147970D01*
X824416Y103545D01*
X920701Y122260D01*
X931201D01*
X935138Y126197D01*
X948918D01*
X952855Y130134D01*
X957634D01*
X962451Y137275D01*
X980849Y231927D01*
X959794Y340321D01*
X956169Y345695D01*
X911268Y381803D01*
X898350Y400960D01*
X867644Y558918D01*
X881975Y632658D01*
X924808Y696166D01*
X927643Y698350D01*
X930662Y698361D01*
G03X931962Y698694I1J2701D01*
G03X932572Y699152I-1301J2367D01*
G01X933379Y699959D01*
G02X933931Y700239I706J-708D01*
G01X933992Y700249D01*
G02X934604Y700151I156J-988D01*
G01X937205Y698818D01*
G01X536024Y91930D02*
Y90404D01*
G03X536679Y89749I655J0D01*
G01X538058D01*
G03X538992Y90683I0J934D01*
G01Y125224D01*
X539180Y125511D01*
X550053Y142026D01*
X564514Y151781D01*
X564515Y151782D01*
Y151781D01*
X607813Y160199D01*
X794264Y121464D01*
X898482Y141722D01*
X898483Y141723D01*
X898839Y142250D01*
X900753Y142622D01*
X901280Y142266D01*
X903195Y142638D01*
X903550Y143166D01*
X905465Y143538D01*
X905992Y143182D01*
X907906Y143554D01*
X908262Y144082D01*
X910176Y144454D01*
X910704Y144098D01*
X912618Y144470D01*
X912974Y144998D01*
X914888Y145370D01*
X915416Y145014D01*
X926294Y147128D01*
X926298Y147129D01*
X926407Y147150D01*
X930663D01*
G03X931408Y147342I-2J1551D01*
G03X931758Y147605I-747J1358D01*
G01X932156Y148003D01*
G03X932342Y148578I-470J470D01*
G03X931983Y149066I-658J-108D01*
G01X929331Y150394D01*
G01X536024Y86418D02*
Y87944D01*
G02X536679Y88599I655J0D01*
G01X538058D01*
G03X540142Y90683I0J2084D01*
G01Y124879D01*
X550887Y141201D01*
X564964Y150696D01*
X607805Y159025D01*
X794256Y120290D01*
X926514Y145998D01*
X926517Y145999D01*
X926522Y146000D01*
X930662D01*
G03X931962Y146333I1J2701D01*
G03X932572Y146791I-1301J2367D01*
G01X933379Y147598D01*
G02X933931Y147878I706J-708D01*
G01X933992Y147888D01*
G02X934604Y147790I156J-988D01*
G01X937205Y146457D01*
G01X528937Y87993D02*
Y86467D01*
G03X529592Y85812I655J0D01*
G01X530971D01*
G03X531905Y86746I0J934D01*
G01Y128180D01*
X542328Y144008D01*
X559970Y157415D01*
X607419Y166638D01*
X773609Y133203D01*
X808204Y139927D01*
X808560Y140455D01*
X810474Y140827D01*
X811001Y140471D01*
X812916Y140843D01*
X813272Y141370D01*
X815186Y141742D01*
X815713Y141386D01*
X817627Y141759D01*
X817983Y142286D01*
X819898Y142658D01*
X820425Y142302D01*
X822339Y142674D01*
X822695Y143202D01*
X824609Y143574D01*
X825137Y143218D01*
X926390Y162898D01*
X930663D01*
G03X931408Y163090I-2J1551D01*
G03X931758Y163353I-747J1358D01*
G01X932156Y163751D01*
G03X932342Y164326I-470J470D01*
G03X931983Y164814I-658J-108D01*
G01X929331Y166142D01*
G01X528937Y82481D02*
Y84007D01*
G02X529592Y84662I655J0D01*
G01X530971D01*
G03X533055Y86746I0J2084D01*
G01Y127835D01*
X538118Y135522D01*
Y135523D01*
X543181Y143211D01*
X560453Y156337D01*
X607415Y165465D01*
X773605Y132030D01*
X926503Y161748D01*
X930662D01*
G03X931962Y162081I1J2701D01*
G03X932572Y162539I-1301J2367D01*
G01X933379Y163346D01*
G02X933931Y163626I706J-708D01*
G01X933992Y163636D01*
G02X934604Y163538I156J-988D01*
G01X937205Y162205D01*
G01X521850Y91930D02*
Y90404D01*
G03X522505Y89749I655J0D01*
G01X523884D01*
G03X524818Y90683I0J934D01*
G01Y129358D01*
X538872Y150700D01*
X557585Y163325D01*
X610879Y173685D01*
X752238Y144078D01*
X800667Y153705D01*
X801020Y154234D01*
X802933Y154614D01*
X803462Y154261D01*
X805375Y154641D01*
X805728Y155170D01*
X807641Y155550D01*
X808170Y155196D01*
X810083Y155577D01*
X810436Y156106D01*
X812349Y156486D01*
X812878Y156132D01*
X814790Y156513D01*
X815144Y157042D01*
X817057Y157422D01*
X817586Y157068D01*
X926138Y178646D01*
X930663D01*
G03X931408Y178838I-2J1551D01*
G03X931758Y179101I-747J1358D01*
G01X932156Y179499D01*
G03X932342Y180074I-470J470D01*
G03X931983Y180562I-658J-108D01*
G01X929331Y181890D01*
G01X521850Y86418D02*
Y87944D01*
G02X522505Y88599I655J0D01*
G01X523884D01*
G03X525968Y90683I0J2084D01*
G01Y129013D01*
X539706Y149874D01*
X558035Y162240D01*
X610871Y172511D01*
X752232Y142904D01*
X926252Y177496D01*
X930662D01*
G03X931962Y177829I1J2701D01*
G03X932572Y178287I-1301J2367D01*
G01X933379Y179094D01*
G02X933931Y179374I706J-708D01*
G01X933992Y179384D01*
G02X934604Y179286I156J-988D01*
G01X937205Y177953D01*
G01X514764Y87993D02*
Y86467D01*
G03X515419Y85812I655J0D01*
G01X516798D01*
G03X517732Y86746I0J934D01*
G01Y130233D01*
X534033Y154993D01*
X555589Y169538D01*
X613600Y180814D01*
X719999Y158529D01*
X868506Y188048D01*
X868860Y188577D01*
X870772Y188957D01*
X871301Y188604D01*
X873214Y188984D01*
X873568Y189513D01*
X875480Y189893D01*
X876009Y189540D01*
X877922Y189920D01*
X878275Y190449D01*
X880188Y190829D01*
X880717Y190475D01*
X882630Y190856D01*
X882983Y191385D01*
X884896Y191765D01*
X885425Y191411D01*
X900432Y194394D01*
X930663D01*
G03X931408Y194586I-2J1551D01*
G03X931758Y194849I-747J1358D01*
G01X932156Y195247D01*
G03X932342Y195822I-470J470D01*
G03X931983Y196310I-658J-108D01*
G01X929331Y197638D01*
G01X514764Y82481D02*
Y84007D01*
G02X515419Y84662I655J0D01*
G01X516798D01*
G03X518882Y86746I0J2084D01*
G01Y129888D01*
X534867Y154168D01*
X556039Y168453D01*
X613591Y179640D01*
X719993Y157355D01*
X868731Y186919D01*
X868730Y186920D01*
X900546Y193244D01*
X930662D01*
G03X931962Y193577I1J2701D01*
G03X932572Y194035I-1301J2367D01*
G01X933379Y194842D01*
G02X933931Y195122I706J-708D01*
G01X933992Y195132D01*
G02X934604Y195034I156J-988D01*
G01X937205Y193701D01*
G01X564370Y91930D02*
Y90404D01*
G03X565025Y89749I655J0D01*
G01X568560D01*
X610744Y81296D01*
X726562Y104313D01*
X835926Y81404D01*
X928450Y99788D01*
X930724D01*
X934661Y103725D01*
X948441D01*
X952378Y107662D01*
X956073D01*
X972344Y117852D01*
X978702Y127279D01*
X1000059Y237117D01*
X979513Y342823D01*
X969721Y357343D01*
X925676Y392762D01*
X916895Y405778D01*
X886833Y560376D01*
X896057Y607831D01*
X913953Y634365D01*
X913832Y634990D01*
X914922Y636606D01*
X915547Y636728D01*
X916637Y638345D01*
X916516Y638969D01*
X917606Y640586D01*
X918231Y640707D01*
X919321Y642324D01*
X919200Y642949D01*
X920290Y644565D01*
X920915Y644687D01*
X922005Y646304D01*
X921884Y646928D01*
X922974Y648545D01*
X923599Y648666D01*
X924689Y650283D01*
X927251Y652256D01*
X929404Y652267D01*
X930663D01*
G03X931408Y652459I-2J1551D01*
G03X931758Y652722I-747J1358D01*
G01X932156Y653120D01*
G03X932342Y653695I-470J470D01*
G03X931983Y654183I-658J-108D01*
G01X929331Y655511D01*
G01X564370Y86418D02*
Y87944D01*
G02X565025Y88599I655J0D01*
G01X568445D01*
X610743Y80123D01*
X726556Y103139D01*
X835920Y80230D01*
X882413Y89468D01*
X928564Y98638D01*
X931201D01*
X935138Y102575D01*
X948918D01*
X952855Y106512D01*
X956404D01*
X973162Y117006D01*
X979787Y126830D01*
Y126829D01*
X1001231Y237117D01*
X980598Y343272D01*
X970578Y358131D01*
X926533Y393550D01*
X917980Y406228D01*
X888005Y560376D01*
X892574Y583880D01*
X897142Y607382D01*
X925539Y649485D01*
X927643Y651106D01*
X929830Y651117D01*
X930662D01*
G03X931962Y651450I1J2701D01*
G03X932572Y651908I-1301J2367D01*
G01X933379Y652715D01*
G02X933931Y652995I706J-708D01*
G01X933992Y653005D01*
G02X934604Y652907I156J-988D01*
G01X937205Y651574D01*
G01X557283Y87993D02*
Y86467D01*
G03X557938Y85812I655J0D01*
G01X558764D01*
G03X560251Y87299I0J1487D01*
G01Y124741D01*
X561671Y126898D01*
X564403Y128741D01*
X599070Y135480D01*
X835359Y89546D01*
X927945Y107662D01*
X930725D01*
X934662Y111599D01*
X948441D01*
X952378Y115536D01*
X956364D01*
X966496Y121884D01*
X972957Y131462D01*
X993485Y237057D01*
X973354Y340619D01*
X964761Y353359D01*
X920141Y389112D01*
X910376Y403597D01*
X879979Y559962D01*
X891027Y616797D01*
X912224Y648226D01*
X912102Y648850D01*
X913193Y650467D01*
X913817Y650589D01*
X914908Y652205D01*
X914786Y652830D01*
X915877Y654447D01*
X916501Y654568D01*
X917592Y656185D01*
X917470Y656809D01*
X918560Y658426D01*
X919185Y658548D01*
X920276Y660164D01*
X920154Y660789D01*
X921244Y662406D01*
X921869Y662527D01*
X923634Y665144D01*
X923738Y665298D01*
X927251Y668004D01*
X930663Y668015D01*
G03X931408Y668207I-2J1551D01*
G03X931758Y668470I-747J1358D01*
G01X932156Y668868D01*
G03X932342Y669443I-470J470D01*
G03X931983Y669931I-658J-108D01*
G01X929331Y671259D01*
G01X557283Y82481D02*
Y84007D01*
G02X557938Y84662I655J0D01*
G01X558764D01*
G03X561401Y87299I0J2637D01*
G01Y124396D01*
X562505Y126073D01*
X564852Y127656D01*
X599070Y134308D01*
X835360Y88374D01*
X928057Y106512D01*
X931202D01*
X935139Y110449D01*
X948917D01*
X949463Y110994D01*
X952855Y114386D01*
X956695D01*
X967314Y121038D01*
X974042Y131012D01*
X994657Y237057D01*
X974439Y341068D01*
X965617Y354147D01*
X920997Y389900D01*
X911461Y404046D01*
X881151Y559962D01*
X892112Y616348D01*
X924588Y664500D01*
X927643Y666854D01*
X930662Y666865D01*
G03X931962Y667198I1J2701D01*
G03X932572Y667656I-1301J2367D01*
G01X933379Y668463D01*
G02X933931Y668743I706J-708D01*
G01X933992Y668753D01*
G02X934604Y668655I156J-988D01*
G01X937205Y667322D01*
G01X826772Y1602363D02*
Y1603817D01*
G03X826301Y1604498I-728J0D01*
G03X826054Y1604543I-247J-654D01*
G01X824590D01*
G03X824012Y1604289I0J-785D01*
G03X823804Y1603757I578J-533D01*
G01Y1597484D01*
X812867Y1549135D01*
X821725Y1509142D01*
X799330Y1410157D01*
X805608Y1381807D01*
X797079Y1344071D01*
X1035427Y558561D01*
X1035988Y558261D01*
X1036554Y556395D01*
X1036254Y555834D01*
X1036820Y553968D01*
X1037382Y553668D01*
X1037948Y551802D01*
X1037648Y551241D01*
X1037649Y551238D01*
X1038214Y549375D01*
X1041636Y544105D01*
X1042259Y543973D01*
X1043321Y542338D01*
X1043189Y541715D01*
X1044251Y540080D01*
X1044873Y539947D01*
X1045935Y538312D01*
X1045803Y537690D01*
X1046865Y536054D01*
X1047487Y535922D01*
X1048549Y534286D01*
X1048417Y533664D01*
X1049479Y532029D01*
X1050102Y531896D01*
X1051164Y530261D01*
X1051031Y529638D01*
X1061924Y512865D01*
X1062547Y512733D01*
X1063609Y511097D01*
X1063476Y510475D01*
X1064538Y508839D01*
X1065161Y508707D01*
X1066223Y507072D01*
X1066091Y506449D01*
X1067153Y504814D01*
X1067775Y504681D01*
X1068837Y503046D01*
X1068705Y502424D01*
X1069767Y500788D01*
X1070389Y500656D01*
X1071451Y499020D01*
X1071319Y498398D01*
X1082038Y481893D01*
X1082715Y481749D01*
X1083778Y480113D01*
X1083633Y479436D01*
X1084695Y477800D01*
X1085373Y477656D01*
X1086435Y476021D01*
X1086291Y475343D01*
X1087353Y473707D01*
X1088031Y473563D01*
X1089093Y471928D01*
X1088949Y471250D01*
X1092669Y465522D01*
X1095588Y463174D01*
X1099109D01*
G03X1100282Y463660I0J1659D01*
G01X1100573Y464240D01*
Y464241D01*
G03X1100283Y465113I-581J291D01*
G01X1097441Y466535D01*
G01X826772Y1607874D02*
Y1606420D01*
G02X826045Y1605693I-727J0D01*
G01X824590D01*
G03X823166Y1605068I0J-1935D01*
G03X822654Y1603758I1424J-1312D01*
G01Y1597613D01*
X811688Y1549138D01*
X820546Y1509145D01*
X798151Y1410160D01*
X804429Y1381810D01*
X795890Y1344028D01*
X1037160Y548885D01*
X1091804Y464741D01*
X1095182Y462024D01*
X1099110D01*
G03X1101238Y463000I-1J2809D01*
G01X1101436Y463394D01*
X1101603Y463728D01*
G02X1102475Y464019I581J-290D01*
G01X1105315Y462598D01*
G01X833859Y1598425D02*
Y1599880D01*
G03X833388Y1600561I-728J0D01*
G03X833141Y1600606I-247J-654D01*
G01X831677D01*
G03X831099Y1600352I0J-785D01*
G03X830891Y1599820I578J-533D01*
G01Y1594864D01*
X820108Y1547186D01*
X828420Y1509663D01*
X806157Y1411287D01*
X812455Y1382853D01*
X803888Y1344957D01*
X915838Y975983D01*
X915837D01*
X1027786Y607009D01*
X1028347Y606709D01*
X1028913Y604843D01*
X1028613Y604281D01*
X1029180Y602415D01*
X1029741Y602115D01*
X1030307Y600249D01*
X1030007Y599688D01*
X1035814Y580550D01*
X1036375Y580250D01*
X1036941Y578384D01*
X1036641Y577822D01*
X1037207Y575956D01*
X1037769Y575656D01*
X1038335Y573790D01*
X1038035Y573229D01*
X1038601Y571363D01*
X1039162Y571063D01*
X1039728Y569197D01*
X1039428Y568636D01*
X1039993Y566776D01*
X1039995Y566770D01*
X1040556Y566470D01*
X1041122Y564604D01*
X1040822Y564043D01*
X1040823Y564040D01*
X1043342Y555737D01*
X1059426Y530969D01*
X1060049Y530837D01*
X1061111Y529201D01*
X1060978Y528579D01*
X1062040Y526943D01*
X1062663Y526811D01*
X1063725Y525176D01*
X1063593Y524553D01*
X1064655Y522918D01*
X1065277Y522785D01*
X1066339Y521150D01*
X1066207Y520528D01*
X1067269Y518892D01*
X1067891Y518760D01*
X1068953Y517124D01*
X1068821Y516502D01*
X1079540Y499997D01*
X1080217Y499853D01*
X1081280Y498217D01*
X1081135Y497540D01*
X1082197Y495904D01*
X1082875Y495760D01*
X1083937Y494125D01*
X1083793Y493447D01*
X1084855Y491811D01*
X1085533Y491667D01*
X1086595Y490032D01*
X1086451Y489354D01*
X1090171Y483626D01*
X1096021Y478922D01*
X1099109D01*
G03X1100282Y479408I0J1659D01*
G01X1100573Y479988D01*
Y479989D01*
G03X1100283Y480861I-581J291D01*
G01X1097441Y482283D01*
G01X833859Y1603937D02*
Y1602483D01*
G02X833132Y1601756I-727J0D01*
G01X831677D01*
G03X829741Y1599820I0J-1936D01*
G01Y1594993D01*
X818929Y1547189D01*
X827241Y1509666D01*
X804978Y1411290D01*
X811276Y1382856D01*
X802699Y1344914D01*
X1027512Y603949D01*
X1027513Y603946D01*
X1034712Y580217D01*
X1034713Y580214D01*
X1037499Y571030D01*
X1037500Y571027D01*
X1039720Y563710D01*
X1039721Y563707D01*
X1042288Y555247D01*
X1089306Y482845D01*
X1095615Y477772D01*
X1099110D01*
G03X1101238Y478748I-1J2809D01*
G01X1101436Y479142D01*
X1101603Y479476D01*
G02X1102475Y479767I581J-290D01*
G01X1105315Y478346D01*
G01X840945Y1602363D02*
Y1603817D01*
G03X840474Y1604498I-728J0D01*
G03X840227Y1604543I-247J-654D01*
G01X838763D01*
G03X838185Y1604289I0J-785D01*
G03X837977Y1603757I578J-533D01*
G01Y1594266D01*
X826975Y1545644D01*
X834904Y1509849D01*
X812581Y1411233D01*
X818894Y1382728D01*
X811054Y1348041D01*
X1035468Y608383D01*
X1036029Y608083D01*
X1036595Y606217D01*
X1036295Y605656D01*
X1036861Y603790D01*
X1037423Y603490D01*
X1037989Y601624D01*
X1037689Y601062D01*
X1037690Y601059D01*
X1043496Y581924D01*
X1044057Y581624D01*
X1044623Y579758D01*
X1044323Y579197D01*
X1044889Y577331D01*
X1045450Y577031D01*
X1046017Y575165D01*
X1045717Y574603D01*
X1046283Y572737D01*
X1046844Y572438D01*
X1047410Y570572D01*
X1047110Y570010D01*
X1047111Y570007D01*
X1047676Y568144D01*
X1048238Y567844D01*
X1048804Y565978D01*
X1048504Y565417D01*
X1049070Y563551D01*
X1059687Y547038D01*
X1060309Y546902D01*
X1061364Y545262D01*
X1061228Y544640D01*
X1062283Y543000D01*
X1062905Y542865D01*
X1063959Y541225D01*
X1063824Y540603D01*
X1064879Y538963D01*
X1065501Y538827D01*
X1066555Y537187D01*
X1066420Y536565D01*
X1067475Y534925D01*
X1068097Y534790D01*
X1069151Y533150D01*
X1069016Y532528D01*
X1076877Y520302D01*
X1077554Y520155D01*
X1078609Y518514D01*
X1078461Y517837D01*
X1079516Y516197D01*
X1080193Y516050D01*
X1081248Y514410D01*
X1081101Y513733D01*
X1082155Y512092D01*
X1082832Y511945D01*
X1083887Y510305D01*
X1083740Y509628D01*
X1090216Y499555D01*
X1096290Y494670D01*
X1099109D01*
G03X1100282Y495156I0J1659D01*
G01X1100573Y495736D01*
Y495737D01*
G03X1100283Y496609I-581J291D01*
G01X1097441Y498031D01*
G01X840945Y1607874D02*
Y1606420D01*
G02X840218Y1605693I-727J0D01*
G01X838763D01*
G03X836827Y1603757I0J-1936D01*
G01Y1594395D01*
X825796Y1545647D01*
X833725Y1509852D01*
X811402Y1411236D01*
X817715Y1382731D01*
X809865Y1347998D01*
X1035759Y603457D01*
X1035760Y603454D01*
X1043787Y576998D01*
X1043788Y576995D01*
X1048015Y563063D01*
X1089349Y498775D01*
X1095884Y493520D01*
X1099110D01*
G03X1101238Y494496I-1J2809D01*
G01X1101436Y494890D01*
X1101603Y495224D01*
G02X1102475Y495515I581J-290D01*
G01X1105315Y494094D01*
G01X848032Y1598425D02*
Y1599880D01*
G03X847561Y1600561I-728J0D01*
G03X847314Y1600606I-247J-654D01*
G01X845850D01*
G03X845272Y1600352I0J-785D01*
G03X845064Y1599820I578J-533D01*
G01Y1595812D01*
X835795Y1554827D01*
X843695Y1519162D01*
X819231Y1411063D01*
X825391Y1383244D01*
X817829Y1349784D01*
X1041210Y613524D01*
X1041771Y613224D01*
X1042337Y611358D01*
X1042037Y610797D01*
X1042603Y608931D01*
X1043165Y608631D01*
X1043731Y606765D01*
X1043431Y606203D01*
X1049238Y587065D01*
X1049799Y586765D01*
X1050365Y584899D01*
X1050065Y584338D01*
X1050631Y582472D01*
X1051192Y582172D01*
X1051759Y580306D01*
X1051459Y579744D01*
X1051460Y579741D01*
X1052025Y577878D01*
X1052586Y577579D01*
X1053152Y575713D01*
X1052852Y575151D01*
X1053418Y573285D01*
X1053980Y572985D01*
X1054546Y571119D01*
X1054246Y570558D01*
X1054248Y570552D01*
X1054812Y568692D01*
X1059473Y561511D01*
X1060096Y561379D01*
X1061157Y559743D01*
X1061025Y559121D01*
X1062086Y557485D01*
X1062709Y557353D01*
X1063771Y555717D01*
X1063638Y555095D01*
X1064700Y553459D01*
X1065322Y553327D01*
X1066384Y551691D01*
X1066252Y551069D01*
X1067313Y549433D01*
X1067936Y549300D01*
X1068997Y547665D01*
X1068865Y547042D01*
X1078770Y531783D01*
X1079448Y531639D01*
X1080509Y530003D01*
X1080365Y529326D01*
X1081427Y527690D01*
X1082105Y527546D01*
X1083166Y525910D01*
X1083022Y525232D01*
X1084084Y523597D01*
X1084762Y523452D01*
X1085823Y521817D01*
X1085679Y521139D01*
X1090208Y514162D01*
X1094864Y510418D01*
X1099109D01*
G03X1100282Y510904I0J1659D01*
G01X1100573Y511484D01*
Y511485D01*
G03X1100283Y512357I-581J291D01*
G01X1097441Y513779D01*
G01X848032Y1603937D02*
Y1602483D01*
G02X847305Y1601756I-727J0D01*
G01X845850D01*
G03X844426Y1601131I0J-1935D01*
G03X843914Y1599820I1424J-1312D01*
G01Y1595941D01*
X834616Y1554830D01*
X842516Y1519165D01*
X818052Y1411066D01*
X821188Y1396905D01*
X821187D01*
X824212Y1383247D01*
X816640Y1349741D01*
X1040109Y613191D01*
X1040108D01*
X1049529Y582139D01*
X1049530Y582136D01*
X1050923Y577545D01*
X1050924Y577542D01*
X1053145Y570222D01*
X1053146Y570219D01*
X1053758Y568202D01*
X1089343Y513381D01*
X1094459Y509268D01*
X1099110D01*
G03X1101238Y510244I-1J2809D01*
G01X1101436Y510638D01*
X1101603Y510972D01*
G02X1102475Y511263I581J-290D01*
G01X1105315Y509842D01*
G01X855118Y1602363D02*
Y1603817D01*
G03X854647Y1604498I-728J0D01*
G03X854400Y1604543I-247J-654D01*
G01X852936D01*
G03X852358Y1604289I0J-785D01*
G03X852150Y1603757I578J-533D01*
G01Y1592794D01*
X843051Y1552558D01*
X850383Y1519453D01*
X825852Y1411145D01*
X831989Y1383434D01*
X824752Y1351409D01*
X1025868Y687791D01*
X1032968Y676858D01*
X1033591Y676726D01*
X1034653Y675090D01*
X1034520Y674468D01*
X1035582Y672833D01*
X1036205Y672700D01*
X1037267Y671065D01*
X1037134Y670442D01*
X1038196Y668807D01*
X1038819Y668674D01*
X1039881Y667039D01*
X1039748Y666417D01*
X1040810Y664781D01*
X1041433Y664649D01*
X1042495Y663013D01*
X1042363Y662391D01*
X1053255Y645617D01*
X1053877Y645485D01*
X1054939Y643849D01*
X1054807Y643227D01*
X1055869Y641591D01*
X1056491Y641459D01*
X1057553Y639824D01*
X1057421Y639201D01*
X1058483Y637566D01*
X1059106Y637433D01*
X1060168Y635798D01*
X1060035Y635175D01*
X1061097Y633540D01*
X1061720Y633408D01*
X1062782Y631772D01*
X1062649Y631150D01*
X1075760Y610959D01*
X1076438Y610815D01*
X1077500Y609180D01*
X1077356Y608502D01*
X1078418Y606867D01*
X1079095Y606723D01*
X1080157Y605087D01*
X1080013Y604409D01*
X1081075Y602774D01*
X1081753Y602630D01*
X1082815Y600994D01*
X1082671Y600317D01*
X1083998Y598273D01*
X1085518Y597051D01*
X1086150Y597120D01*
X1087670Y595897D01*
X1087738Y595265D01*
X1089258Y594043D01*
X1089891Y594111D01*
X1091410Y592889D01*
X1091479Y592256D01*
X1095331Y589158D01*
X1099109D01*
G03X1100282Y589644I0J1659D01*
G01X1100573Y590224D01*
Y590225D01*
G03X1100283Y591097I-581J291D01*
G01X1097441Y592519D01*
G01X855118Y1607874D02*
Y1606420D01*
G02X854391Y1605693I-727J0D01*
G01X852936D01*
G03X851512Y1605068I0J-1935D01*
G03X851000Y1603757I1424J-1312D01*
G01Y1592923D01*
X841872Y1552561D01*
X849204Y1519456D01*
X824673Y1411148D01*
X830810Y1383437D01*
X823563Y1351366D01*
X924209Y1019267D01*
Y1019266D01*
X1024814Y687301D01*
X1083133Y597492D01*
X1094925Y588008D01*
X1099110D01*
G03X1101238Y588984I-1J2809D01*
G01X1101436Y589378D01*
X1101603Y589712D01*
G02X1102475Y590003I581J-290D01*
G01X1105315Y588582D01*
G01X862205Y1598425D02*
Y1599880D01*
G03X861734Y1600561I-728J0D01*
G03X861487Y1600606I-247J-654D01*
G01X860023D01*
G03X859445Y1600352I0J-785D01*
G03X859237Y1599820I578J-533D01*
G01Y1593327D01*
X852816Y1564961D01*
X860077Y1532181D01*
X832480Y1410241D01*
X838392Y1383534D01*
X831175Y1351599D01*
X931022Y1022510D01*
X931023Y1022507D01*
X1030869Y693420D01*
X1033953Y688671D01*
X1034576Y688538D01*
X1035638Y686903D01*
X1035505Y686281D01*
X1036567Y684645D01*
X1037190Y684513D01*
X1038252Y682877D01*
X1038120Y682255D01*
X1049012Y665481D01*
X1049634Y665349D01*
X1050696Y663713D01*
X1050564Y663091D01*
X1051626Y661455D01*
X1052248Y661323D01*
X1053310Y659688D01*
X1053178Y659065D01*
X1054240Y657430D01*
X1054863Y657297D01*
X1055925Y655662D01*
X1055792Y655039D01*
X1056854Y653404D01*
X1057477Y653272D01*
X1058539Y651636D01*
X1058406Y651014D01*
X1069298Y634240D01*
X1069921Y634108D01*
X1070983Y632472D01*
X1070851Y631850D01*
X1071913Y630214D01*
X1072535Y630082D01*
X1073597Y628446D01*
X1073465Y627824D01*
X1074527Y626188D01*
X1075149Y626056D01*
X1076211Y624421D01*
X1076079Y623798D01*
X1077141Y622163D01*
X1077763Y622030D01*
X1078825Y620395D01*
X1078693Y619772D01*
X1079755Y618137D01*
X1081275Y616915D01*
X1081963Y616990D01*
X1083483Y615767D01*
X1083558Y615079D01*
X1085077Y613856D01*
X1085766Y613931D01*
X1087286Y612709D01*
X1087360Y612020D01*
X1088880Y610798D01*
X1089569Y610873D01*
X1091088Y609651D01*
X1091163Y608962D01*
X1096206Y604906D01*
X1099109D01*
G03X1100282Y605392I0J1659D01*
G01X1100573Y605972D01*
Y605973D01*
G03X1100283Y606845I-581J291D01*
G01X1097441Y608267D01*
G01X862205Y1603937D02*
Y1602483D01*
G02X861478Y1601756I-727J0D01*
G01X860023D01*
G03X858087Y1599820I0J-1936D01*
G01Y1593456D01*
X851637Y1564964D01*
X858898Y1532184D01*
X831301Y1410244D01*
X834313Y1396639D01*
X834312D01*
X837213Y1383537D01*
X829986Y1351556D01*
X929921Y1022176D01*
X929922Y1022174D01*
X1029815Y692930D01*
X1078890Y617356D01*
X1095800Y603756D01*
X1099110D01*
G03X1101238Y604732I-1J2809D01*
G01X1101436Y605126D01*
X1101603Y605460D01*
G02X1102475Y605751I581J-290D01*
G01X1105315Y604330D01*
G01X869292Y1607874D02*
Y1606420D01*
G02X868565Y1605693I-727J0D01*
G01X867110D01*
G03X865686Y1605068I0J-1935D01*
G03X865174Y1603757I1424J-1312D01*
G01Y1591376D01*
X858578Y1562692D01*
X865715Y1530487D01*
X838168Y1408783D01*
X843668Y1383954D01*
X836598Y1352667D01*
X1032521Y706916D01*
X1032522Y706913D01*
X1034743Y699593D01*
X1034744Y699590D01*
X1035356Y697573D01*
X1075403Y635906D01*
X1095800Y619504D01*
X1099110D01*
G03X1101238Y620480I-1J2809D01*
G01X1101436Y620874D01*
X1101603Y621208D01*
G02X1102475Y621499I581J-290D01*
G01X1105315Y620078D01*
G01X869292Y1602363D02*
Y1603817D01*
G03X868821Y1604498I-728J0D01*
G03X868574Y1604543I-247J-654D01*
G01X867110D01*
G03X866532Y1604289I0J-785D01*
G03X866324Y1603757I578J-533D01*
G01Y1591245D01*
X859758Y1562687D01*
X866894Y1530484D01*
X839347Y1408780D01*
X844847Y1383951D01*
X837787Y1352710D01*
X1033623Y707249D01*
X1034184Y706950D01*
X1034750Y705084D01*
X1034450Y704522D01*
X1035016Y702656D01*
X1035578Y702356D01*
X1036144Y700490D01*
X1035844Y699929D01*
X1035846Y699923D01*
X1036410Y698063D01*
X1045523Y684030D01*
X1046146Y683898D01*
X1047208Y682262D01*
X1047075Y681640D01*
X1048137Y680004D01*
X1048760Y679872D01*
X1049822Y678237D01*
X1049690Y677614D01*
X1050752Y675979D01*
X1051374Y675846D01*
X1052436Y674211D01*
X1052304Y673589D01*
X1053366Y671953D01*
X1053988Y671821D01*
X1055050Y670185D01*
X1054918Y669563D01*
X1065811Y652789D01*
X1066433Y652657D01*
X1067495Y651022D01*
X1067363Y650399D01*
X1068425Y648764D01*
X1069048Y648632D01*
X1070110Y646996D01*
X1069977Y646374D01*
X1071039Y644738D01*
X1071662Y644606D01*
X1072724Y642971D01*
X1072592Y642348D01*
X1073654Y640713D01*
X1074276Y640580D01*
X1075338Y638945D01*
X1075206Y638322D01*
X1076268Y636687D01*
X1077788Y635465D01*
X1078477Y635540D01*
X1079996Y634318D01*
X1080071Y633629D01*
X1081591Y632407D01*
X1082279Y632482D01*
X1083799Y631260D01*
X1083874Y630571D01*
X1085394Y629349D01*
X1086082Y629424D01*
X1087602Y628202D01*
X1087677Y627513D01*
X1096206Y620654D01*
X1099109D01*
G03X1100282Y621140I0J1659D01*
G01X1100573Y621720D01*
Y621721D01*
G03X1100283Y622593I-581J291D01*
G01X1097441Y624015D01*
G01X876378Y1598425D02*
Y1599880D01*
G03X875907Y1600561I-728J0D01*
G03X875660Y1600606I-247J-654D01*
G01X874196D01*
G03X873618Y1600352I0J-785D01*
G03X873410Y1599820I578J-533D01*
G01Y1593562D01*
X866355Y1562369D01*
X873813Y1528689D01*
X846707Y1408945D01*
X851501Y1384784D01*
X844460Y1353630D01*
X1027386Y750717D01*
X1027947Y750417D01*
X1028513Y748551D01*
X1028213Y747990D01*
X1028779Y746124D01*
X1029341Y745824D01*
X1029907Y743958D01*
X1029607Y743396D01*
X1035414Y724258D01*
X1035975Y723958D01*
X1036541Y722092D01*
X1036241Y721531D01*
X1036807Y719665D01*
X1037368Y719365D01*
X1037935Y717499D01*
X1037635Y716937D01*
X1037636Y716934D01*
X1038201Y715071D01*
X1038762Y714772D01*
X1039328Y712906D01*
X1039028Y712344D01*
X1039594Y710478D01*
X1040156Y710178D01*
X1040722Y708312D01*
X1040422Y707751D01*
X1040424Y707745D01*
X1040988Y705885D01*
X1047397Y696016D01*
X1048019Y695884D01*
X1049081Y694248D01*
X1048949Y693626D01*
X1050011Y691990D01*
X1050633Y691858D01*
X1051695Y690223D01*
X1051563Y689600D01*
X1052625Y687965D01*
X1053248Y687832D01*
X1054310Y686197D01*
X1054177Y685574D01*
X1055239Y683939D01*
X1055862Y683807D01*
X1056924Y682171D01*
X1056791Y681549D01*
X1068345Y663756D01*
X1069023Y663612D01*
X1070085Y661976D01*
X1069941Y661298D01*
X1071003Y659663D01*
X1071681Y659519D01*
X1072743Y657883D01*
X1072599Y657206D01*
X1073661Y655570D01*
X1074338Y655426D01*
X1075400Y653791D01*
X1075256Y653113D01*
X1078140Y648672D01*
X1093397Y636402D01*
X1099109D01*
G03X1100282Y636888I0J1659D01*
G01X1100573Y637468D01*
Y637469D01*
G03X1100283Y638341I-581J291D01*
G01X1097441Y639763D01*
G01X876378Y1603937D02*
Y1602483D01*
G02X875651Y1601756I-727J0D01*
G01X874196D01*
G03X872772Y1601131I0J-1935D01*
G03X872260Y1599820I1424J-1312D01*
G01Y1593691D01*
X865176Y1562372D01*
X872634Y1528692D01*
X845531Y1408961D01*
X850325Y1384800D01*
X843271Y1353587D01*
X1027677Y745791D01*
X1027678Y745788D01*
X1035705Y719332D01*
X1035706Y719329D01*
X1037099Y714738D01*
X1037100Y714735D01*
X1039321Y707415D01*
X1039322Y707412D01*
X1039934Y705395D01*
X1077275Y647891D01*
X1092991Y635252D01*
X1099110D01*
G03X1101238Y636228I-1J2809D01*
G01X1101436Y636622D01*
X1101603Y636956D01*
G02X1102475Y637247I581J-290D01*
G01X1105315Y635826D01*
G01X1504528Y91930D02*
Y90404D01*
G03X1505183Y89749I655J0D01*
G01X1506681D01*
G03X1507496Y90564I0J815D01*
G01Y125561D01*
X1466946Y189161D01*
X1254689Y338058D01*
X1254062Y337948D01*
X1252466Y339067D01*
X1252356Y339694D01*
X1250759Y340814D01*
X1250132Y340704D01*
X1248536Y341824D01*
X1248426Y342451D01*
X1246830Y343571D01*
X1246203Y343461D01*
X1244606Y344581D01*
X1244497Y345207D01*
X1241596Y347242D01*
X1239692Y347664D01*
X1239155Y347322D01*
X1237252Y347744D01*
X1236910Y348281D01*
X1235006Y348703D01*
X1234469Y348361D01*
X1232565Y348783D01*
X1232224Y349320D01*
X1230320Y349742D01*
X1229783Y349400D01*
X1227879Y349822D01*
X1227537Y350358D01*
X1225633Y350781D01*
X1225097Y350439D01*
X1223193Y350861D01*
X1222851Y351397D01*
X1203325Y355726D01*
X1202788Y355384D01*
X1200885Y355806D01*
X1200543Y356343D01*
X1198639Y356765D01*
X1198102Y356423D01*
X1196198Y356845D01*
X1195856Y357381D01*
X1193953Y357803D01*
X1193416Y357461D01*
X1191512Y357884D01*
X1191170Y358420D01*
X1189266Y358842D01*
X1188730Y358500D01*
X1186826Y358922D01*
X1186484Y359459D01*
X1154479Y366554D01*
X1153894Y366182D01*
X1151991Y366604D01*
X1151618Y367188D01*
X1149715Y367610D01*
X1149130Y367238D01*
X1147226Y367660D01*
X1146854Y368245D01*
X1144950Y368667D01*
X1144366Y368294D01*
X1142462Y368716D01*
X1142090Y369301D01*
X1140186Y369723D01*
X1139601Y369351D01*
X1137698Y369773D01*
X1137325Y370357D01*
X1115629Y375167D01*
X1095961Y370809D01*
X1081448Y361563D01*
X1068805Y341716D01*
X1068385Y339812D01*
X1068758Y339228D01*
X1068339Y337323D01*
X1067755Y336950D01*
X1067335Y335046D01*
X1067708Y334462D01*
X1067288Y332558D01*
X1066704Y332185D01*
X1066284Y330281D01*
X1066657Y329697D01*
X1066238Y327792D01*
X1065654Y327419D01*
X1065234Y325515D01*
X1065607Y324931D01*
X1065187Y323027D01*
X1064603Y322654D01*
X1052110Y265979D01*
X1052660Y263494D01*
X1052661Y263493D01*
X1053197Y263151D01*
X1053620Y261247D01*
X1053278Y260710D01*
X1053700Y258807D01*
X1054236Y258465D01*
X1054659Y256561D01*
X1054317Y256024D01*
X1054739Y254120D01*
X1055275Y253779D01*
X1055697Y251875D01*
X1055356Y251338D01*
X1055778Y249434D01*
X1056314Y249092D01*
X1056736Y247189D01*
X1056395Y246652D01*
X1071337Y179260D01*
X1090115Y149781D01*
X1094250Y147150D01*
X1098773D01*
G03X1099518Y147342I-2J1551D01*
G03X1099868Y147605I-747J1358D01*
G01X1100266Y148003D01*
G03X1100452Y148578I-470J470D01*
G03X1100093Y149066I-658J-108D01*
G01X1097441Y150394D01*
G01X1105315Y146457D02*
X1102714Y147790D01*
G03X1102102Y147888I-456J-890D01*
G01X1102041Y147878D01*
G03X1101489Y147598I154J-988D01*
G01X1100682Y146791D01*
G02X1100072Y146333I-1911J1909D01*
G02X1098772Y146000I-1299J2368D01*
G01X1093915D01*
X1089282Y148947D01*
X1070258Y178813D01*
X1051641Y262778D01*
X1051640Y262779D01*
X1050932Y265979D01*
X1067725Y342163D01*
X1080615Y362396D01*
X1080614D01*
X1095514Y371888D01*
X1115629Y376345D01*
X1242069Y348316D01*
X1467793Y189972D01*
X1508646Y125897D01*
Y90564D01*
G02X1506681Y88599I-1965J0D01*
G01X1505183D01*
G03X1504528Y87944I0J-655D01*
G01Y86418D01*
G01X1497441Y87993D02*
Y86467D01*
G03X1498096Y85812I655J0D01*
G01X1499579D01*
G03X1500409Y86642I0J830D01*
G01Y124834D01*
X1465157Y180124D01*
X1246879Y333243D01*
X1246252Y333133D01*
X1244655Y334253D01*
X1244545Y334880D01*
X1242949Y336000D01*
X1242322Y335890D01*
X1240726Y337010D01*
X1240616Y337637D01*
X1239020Y338756D01*
X1238393Y338646D01*
X1236796Y339766D01*
X1236686Y340393D01*
X1235090Y341513D01*
X1205540Y348064D01*
X1205003Y347722D01*
X1203100Y348145D01*
X1202758Y348681D01*
X1200854Y349103D01*
X1200317Y348762D01*
X1198414Y349184D01*
X1198072Y349720D01*
X1196168Y350143D01*
X1195631Y349801D01*
X1193727Y350223D01*
X1193385Y350760D01*
X1191482Y351182D01*
X1190945Y350840D01*
X1189041Y351262D01*
X1188699Y351799D01*
X1169173Y356128D01*
X1168637Y355786D01*
X1166733Y356208D01*
X1166391Y356745D01*
X1164487Y357167D01*
X1163951Y356825D01*
X1162047Y357247D01*
X1161705Y357784D01*
X1159801Y358206D01*
X1159264Y357864D01*
X1157361Y358286D01*
X1157019Y358823D01*
X1155115Y359245D01*
X1154578Y358903D01*
X1152674Y359325D01*
X1152333Y359862D01*
X1133119Y364122D01*
X1132535Y363750D01*
X1130631Y364172D01*
X1130259Y364757D01*
X1128355Y365179D01*
X1127770Y364807D01*
X1125867Y365229D01*
X1125494Y365813D01*
X1123591Y366235D01*
X1123006Y365863D01*
X1121102Y366285D01*
X1120730Y366869D01*
X1118826Y367292D01*
X1118242Y366919D01*
X1116338Y367341D01*
X1115966Y367926D01*
X1114062Y368348D01*
X1100276Y365291D01*
X1085755Y356043D01*
X1077750Y343464D01*
X1077207Y341015D01*
X1077579Y340430D01*
X1077157Y338526D01*
X1076572Y338154D01*
X1076150Y336250D01*
X1076522Y335666D01*
X1076100Y333762D01*
X1075516Y333390D01*
X1075093Y331486D01*
X1075466Y330902D01*
X1075044Y328998D01*
X1074459Y328626D01*
X1074037Y326722D01*
X1074409Y326137D01*
X1073987Y324234D01*
X1073402Y323861D01*
X1059965Y263275D01*
X1060207Y262183D01*
X1060743Y261841D01*
X1061166Y259937D01*
X1060824Y259400D01*
X1061246Y257497D01*
X1061783Y257155D01*
X1062205Y255251D01*
X1061863Y254714D01*
X1062285Y252810D01*
X1062822Y252469D01*
X1063244Y250565D01*
X1062902Y250028D01*
X1063324Y248124D01*
X1063861Y247782D01*
X1064283Y245879D01*
X1063941Y245342D01*
X1076861Y187076D01*
X1090604Y165480D01*
X1094659Y162898D01*
X1098773D01*
G03X1099518Y163090I-2J1551D01*
G03X1099868Y163353I-747J1358D01*
G01X1100266Y163751D01*
G03X1100452Y164326I-470J470D01*
G03X1100093Y164814I-658J-108D01*
G01X1097441Y166142D01*
G01X1497441Y82481D02*
Y84007D01*
G02X1498096Y84662I655J0D01*
G01X1499579D01*
G03X1501559Y86642I0J1980D01*
G01Y125170D01*
X1466004Y180935D01*
X1235563Y342587D01*
X1114062Y369526D01*
X1099829Y366370D01*
X1084921Y356877D01*
X1076671Y343911D01*
X1058786Y263275D01*
X1059187Y261469D01*
X1059186D01*
X1075782Y186629D01*
X1089770Y164646D01*
X1094324Y161748D01*
X1098772D01*
G03X1100072Y162081I1J2701D01*
G03X1100682Y162539I-1301J2367D01*
G01X1101489Y163346D01*
G02X1102041Y163626I706J-708D01*
G01X1102102Y163636D01*
G02X1102714Y163538I156J-988D01*
G01X1105315Y162205D01*
G01X1490354Y91930D02*
Y90404D01*
G03X1491009Y89749I655J0D01*
G01X1492516D01*
G03X1493322Y90555I0J806D01*
G01Y124343D01*
X1493321D01*
X1481445Y143009D01*
X1430545Y176156D01*
X1408825Y209151D01*
X1328178Y261524D01*
X1327500Y261380D01*
X1325864Y262442D01*
X1325720Y263120D01*
X1324085Y264182D01*
X1323407Y264038D01*
X1321772Y265100D01*
X1321627Y265777D01*
X1319992Y266839D01*
X1319314Y266695D01*
X1317679Y267757D01*
X1317535Y268435D01*
X1315899Y269497D01*
X1315222Y269353D01*
X1313586Y270415D01*
X1313442Y271093D01*
X1279114Y293386D01*
X1278436Y293242D01*
X1276801Y294304D01*
X1276656Y294982D01*
X1275021Y296044D01*
X1274343Y295900D01*
X1272708Y296962D01*
X1272564Y297640D01*
X1270928Y298702D01*
X1270250Y298558D01*
X1268615Y299620D01*
X1268471Y300298D01*
X1266836Y301360D01*
X1266158Y301216D01*
X1264522Y302278D01*
X1264378Y302956D01*
X1223619Y329425D01*
X1222941Y329281D01*
X1221306Y330343D01*
X1221162Y331020D01*
X1219526Y332082D01*
X1218848Y331938D01*
X1217213Y333000D01*
X1217069Y333678D01*
X1215433Y334740D01*
X1214756Y334596D01*
X1213120Y335658D01*
X1212976Y336336D01*
X1211341Y337398D01*
X1210663Y337254D01*
X1209027Y338316D01*
X1208883Y338994D01*
X1207248Y340056D01*
X1155957Y350959D01*
X1155376Y350582D01*
X1153469Y350987D01*
X1153091Y351569D01*
X1151184Y351974D01*
X1150603Y351597D01*
X1148696Y352002D01*
X1148318Y352583D01*
X1110427Y360638D01*
X1103342Y359067D01*
X1092142Y351931D01*
X1084323Y339662D01*
X1083901Y337758D01*
X1084273Y337174D01*
X1083851Y335270D01*
X1083266Y334898D01*
X1082844Y332994D01*
X1083216Y332410D01*
X1082794Y330506D01*
X1082209Y330134D01*
X1081787Y328230D01*
X1082159Y327645D01*
X1081737Y325742D01*
X1081153Y325369D01*
X1080730Y323466D01*
X1081103Y322881D01*
X1080680Y320977D01*
X1080096Y320605D01*
X1067171Y262341D01*
X1073927Y231861D01*
X1074464Y231519D01*
X1074886Y229615D01*
X1074544Y229079D01*
X1074966Y227175D01*
X1075502Y226833D01*
X1075924Y224929D01*
X1075582Y224392D01*
X1076004Y222488D01*
X1076541Y222147D01*
X1076963Y220243D01*
X1076621Y219706D01*
X1077043Y217802D01*
X1077580Y217460D01*
X1078002Y215556D01*
X1077660Y215020D01*
X1081942Y195699D01*
X1091351Y180941D01*
X1094956Y178646D01*
X1098773D01*
G03X1099518Y178838I-2J1550D01*
G03X1099868Y179101I-747J1359D01*
G01X1100266Y179499D01*
G03X1100452Y180074I-470J470D01*
G03X1100093Y180562I-658J-108D01*
G01X1097441Y181890D01*
G01X1105315Y177953D02*
X1102714Y179286D01*
G03X1102102Y179384I-456J-890D01*
G01X1102041Y179374D01*
G03X1101489Y179094I154J-988D01*
G01X1100682Y178287D01*
G02X1100072Y177829I-1911J1909D01*
G02X1098772Y177496I-1299J2368D01*
G01X1094620D01*
X1090518Y180108D01*
X1080863Y195252D01*
X1065993Y262341D01*
X1083244Y340109D01*
X1091309Y352764D01*
X1102895Y360146D01*
X1110422Y361815D01*
X1207696Y341137D01*
X1409654Y209985D01*
X1431375Y176989D01*
X1431374D01*
X1482282Y143837D01*
X1494472Y124678D01*
Y90555D01*
G02X1492516Y88599I-1956J0D01*
G01X1491009D01*
G03X1490354Y87944I0J-655D01*
G01Y86418D01*
G01X1097441Y197638D02*
X1100093Y196310D01*
G02X1100452Y195822I-299J-596D01*
G02X1100266Y195247I-656J-105D01*
G01X1099868Y194849D01*
G02X1099518Y194586I-1097J1096D01*
G02X1098773Y194394I-747J1358D01*
G01X1093463D01*
X1090689Y196162D01*
X1088132Y200174D01*
X1079217Y240387D01*
X1079559Y240924D01*
X1079137Y242828D01*
X1078600Y243170D01*
X1078178Y245073D01*
X1078520Y245610D01*
X1078098Y247514D01*
X1077561Y247856D01*
X1077139Y249760D01*
X1077481Y250296D01*
X1077059Y252200D01*
X1076522Y252542D01*
X1076101Y254441D01*
X1076100Y254446D01*
X1076442Y254982D01*
X1076020Y256886D01*
X1075483Y257228D01*
X1075482Y257232D01*
X1075227Y258374D01*
X1077068Y267729D01*
X1077644Y268116D01*
X1078020Y270029D01*
X1077634Y270604D01*
X1078011Y272518D01*
X1078586Y272904D01*
X1078963Y274817D01*
X1078576Y275392D01*
X1078953Y277306D01*
X1079528Y277692D01*
X1079905Y279605D01*
X1079519Y280181D01*
X1079895Y282094D01*
X1080471Y282480D01*
X1080847Y284393D01*
X1080461Y284969D01*
X1086494Y315619D01*
X1087069Y316005D01*
X1087446Y317919D01*
X1087059Y318494D01*
X1087436Y320407D01*
X1088011Y320794D01*
X1088388Y322707D01*
X1088002Y323282D01*
X1088378Y325196D01*
X1088954Y325582D01*
X1089330Y327495D01*
X1088944Y328070D01*
X1089321Y329984D01*
X1089896Y330370D01*
X1090273Y332283D01*
X1089886Y332859D01*
X1090943Y338227D01*
X1096699Y347265D01*
X1105735Y353024D01*
X1109967Y353962D01*
X1194126Y335307D01*
X1194711Y334935D01*
X1194849Y334313D01*
X1196494Y333265D01*
X1197115Y333403D01*
X1198760Y332355D01*
X1198897Y331734D01*
X1200542Y330686D01*
X1201163Y330824D01*
X1202808Y329776D01*
X1202946Y329155D01*
X1204590Y328107D01*
X1205212Y328245D01*
X1206856Y327197D01*
X1206994Y326576D01*
X1208638Y325528D01*
X1209260Y325666D01*
X1256941Y295289D01*
X1257078Y294668D01*
X1258723Y293620D01*
X1259344Y293758D01*
X1260989Y292710D01*
X1261127Y292088D01*
X1262771Y291041D01*
X1263393Y291178D01*
X1265037Y290131D01*
X1265175Y289509D01*
X1266819Y288462D01*
X1267441Y288599D01*
X1269085Y287552D01*
X1269223Y286930D01*
X1270868Y285882D01*
X1271489Y286020D01*
X1296150Y270309D01*
X1296288Y269688D01*
X1297932Y268640D01*
X1298554Y268778D01*
X1300198Y267730D01*
X1300336Y267109D01*
X1301980Y266061D01*
X1302602Y266199D01*
X1304246Y265151D01*
X1304384Y264530D01*
X1306029Y263482D01*
X1306650Y263620D01*
X1405704Y200514D01*
X1423600Y172449D01*
X1476359Y138834D01*
X1486236Y123342D01*
Y86631D01*
G02X1485417Y85812I-819J0D01*
G01X1483923D01*
G02X1483268Y86467I0J655D01*
G01Y87993D01*
G01X1105315Y193701D02*
X1102714Y195034D01*
G03X1102102Y195132I-456J-890D01*
G01X1102041Y195122D01*
G03X1101489Y194842I154J-988D01*
G01X1100682Y194035D01*
G02X1100072Y193577I-1911J1909D01*
G02X1098772Y193244I-1299J2368D01*
G01X1093127D01*
X1089856Y195329D01*
X1087053Y199727D01*
X1074357Y256981D01*
X1074359Y256982D01*
X1074051Y258359D01*
X1089856Y338662D01*
X1095866Y348098D01*
X1105288Y354103D01*
X1109967Y355140D01*
X1194573Y336387D01*
X1406537Y201347D01*
X1424433Y173282D01*
X1477192Y139667D01*
X1487386Y123678D01*
Y86631D01*
G02X1485417Y84662I-1969J0D01*
G01X1483923D01*
G03X1483268Y84007I0J-655D01*
G01Y82481D01*
G01X1518701Y86418D02*
Y87944D01*
G02X1519356Y88599I655J0D01*
G01X1520814D01*
G03X1522819Y90604I0J2005D01*
G01Y135494D01*
X1493590Y177715D01*
X1462079Y251419D01*
X1132095Y731620D01*
X1121259Y740331D01*
X1114782Y742397D01*
X1108161Y744509D01*
X1097464Y741093D01*
X1082992Y729454D01*
X1079109Y714730D01*
X1091576Y685077D01*
X1096008Y682603D01*
X1098772Y682613D01*
G03X1100072Y682946I1J2701D01*
G03X1100682Y683404I-1301J2367D01*
G01X1101489Y684211D01*
G02X1102041Y684491I706J-708D01*
G01X1102102Y684501D01*
G02X1102714Y684403I156J-988D01*
G01X1105315Y683070D01*
G01X1532874Y91930D02*
Y90404D01*
G03X1533529Y89749I655J0D01*
G01X1534948D01*
G03X1535843Y90644I0J895D01*
G01Y151762D01*
X1535031Y155757D01*
X1520045Y178390D01*
X1502539Y219310D01*
X1337442Y459354D01*
X1336761Y459480D01*
X1335656Y461086D01*
X1335782Y461768D01*
X1334677Y463374D01*
X1333996Y463501D01*
X1332890Y465107D01*
X1333017Y465789D01*
X1331912Y467395D01*
X1331230Y467521D01*
X1330125Y469128D01*
X1330251Y469809D01*
X1300720Y512747D01*
X1300094Y512863D01*
X1298989Y514469D01*
X1299105Y515095D01*
X1298000Y516702D01*
X1297374Y516818D01*
X1296269Y518424D01*
X1296385Y519050D01*
X1295280Y520657D01*
X1294654Y520773D01*
X1293549Y522379D01*
X1293665Y523005D01*
X1292560Y524612D01*
X1291934Y524727D01*
X1290829Y526334D01*
X1290945Y526960D01*
X1256794Y576614D01*
X1256168Y576730D01*
X1255063Y578336D01*
X1255179Y578962D01*
X1254074Y580569D01*
X1253448Y580685D01*
X1252343Y582291D01*
X1252459Y582917D01*
X1251354Y584524D01*
X1250728Y584640D01*
X1249623Y586246D01*
X1249739Y586872D01*
X1248634Y588479D01*
X1248008Y588595D01*
X1246903Y590201D01*
X1247018Y590827D01*
X1226525Y620624D01*
X1225899Y620740D01*
X1224794Y622347D01*
X1224910Y622973D01*
X1223805Y624579D01*
X1223179Y624695D01*
X1222074Y626302D01*
X1222190Y626927D01*
X1221085Y628534D01*
X1220459Y628650D01*
X1219354Y630257D01*
X1219470Y630882D01*
X1218365Y632489D01*
X1217739Y632605D01*
X1216634Y634211D01*
X1216750Y634837D01*
X1195147Y666248D01*
X1194466Y666374D01*
X1193361Y667980D01*
X1193487Y668662D01*
X1192382Y670268D01*
X1191700Y670395D01*
X1190595Y672001D01*
X1190722Y672683D01*
X1189616Y674289D01*
X1188935Y674415D01*
X1187830Y676022D01*
X1187956Y676703D01*
X1186851Y678310D01*
X1186170Y678436D01*
X1185065Y680043D01*
X1185191Y680724D01*
X1160826Y716150D01*
X1160200Y716266D01*
X1159095Y717873D01*
X1159211Y718499D01*
X1158106Y720105D01*
X1157480Y720221D01*
X1156375Y721828D01*
X1156491Y722453D01*
X1155386Y724060D01*
X1154760Y724176D01*
X1153655Y725783D01*
X1153771Y726408D01*
X1152666Y728015D01*
X1152040Y728131D01*
X1150935Y729738D01*
X1151051Y730363D01*
X1149743Y732265D01*
X1125645Y751637D01*
X1108339Y757176D01*
X1093462Y752429D01*
Y752430D01*
X1072472Y735544D01*
Y735543D01*
X1066248Y711953D01*
X1090151Y655090D01*
X1095230Y652256D01*
X1098768Y652267D01*
X1098773D01*
G03X1099518Y652459I-2J1551D01*
G03X1099868Y652722I-747J1358D01*
G01X1100266Y653120D01*
G03X1100452Y653695I-470J470D01*
G03X1100093Y654183I-658J-108D01*
G01X1097441Y655511D01*
G01X1532874Y86418D02*
Y87944D01*
G02X1533529Y88599I655J0D01*
G01X1534948D01*
G03X1536993Y90644I0J2045D01*
G01Y151878D01*
X1536114Y156206D01*
X1521062Y178939D01*
X1503552Y219868D01*
X1150595Y733056D01*
X1126199Y752668D01*
X1108340Y758384D01*
X1093113Y753527D01*
X1092908Y753461D01*
X1071456Y736203D01*
X1065036Y711868D01*
X1089244Y654279D01*
X1094934Y651103D01*
X1098772Y651117D01*
G03X1100072Y651450I1J2701D01*
G03X1100682Y651908I-1301J2367D01*
G01X1101489Y652715D01*
G02X1102041Y652995I706J-708D01*
G01X1102102Y653005D01*
G02X1102714Y652907I156J-988D01*
G01X1105315Y651574D01*
G01X1525787Y87993D02*
Y86467D01*
G03X1526442Y85812I655J0D01*
G01X1527868D01*
G03X1528755Y86699I0J887D01*
G01Y135843D01*
X1517203Y152519D01*
X1498452Y179590D01*
X1464429Y259136D01*
X1330690Y453710D01*
X1330009Y453836D01*
X1328904Y455443D01*
X1329030Y456124D01*
X1327926Y457731D01*
X1327244Y457858D01*
X1326140Y459465D01*
X1326266Y460146D01*
X1325162Y461753D01*
X1324480Y461879D01*
X1323376Y463486D01*
X1323502Y464168D01*
X1293752Y507449D01*
X1293126Y507565D01*
X1292021Y509172D01*
X1292137Y509798D01*
X1291033Y511405D01*
X1290407Y511521D01*
X1289302Y513128D01*
X1289418Y513753D01*
X1288314Y515360D01*
X1287688Y515476D01*
X1286583Y517083D01*
X1286699Y517709D01*
X1285595Y519316D01*
X1284969Y519432D01*
X1283865Y521039D01*
X1283981Y521665D01*
X1250064Y571010D01*
X1249439Y571126D01*
X1248334Y572733D01*
X1248450Y573359D01*
X1247345Y574966D01*
X1246720Y575082D01*
X1245615Y576689D01*
X1245731Y577314D01*
X1244626Y578921D01*
X1244001Y579037D01*
X1242896Y580644D01*
X1243012Y581270D01*
X1241907Y582877D01*
X1241282Y582993D01*
X1240177Y584600D01*
X1240293Y585226D01*
X1219527Y615437D01*
X1218901Y615553D01*
X1217796Y617160D01*
X1217912Y617786D01*
X1216808Y619393D01*
X1216182Y619509D01*
X1215077Y621116D01*
X1215193Y621742D01*
X1214089Y623349D01*
X1213463Y623465D01*
X1212358Y625072D01*
X1212474Y625697D01*
X1211370Y627304D01*
X1210744Y627420D01*
X1209639Y629027D01*
X1209755Y629653D01*
X1188157Y661076D01*
X1187476Y661202D01*
X1186371Y662809D01*
X1186498Y663490D01*
X1185393Y665097D01*
X1184712Y665224D01*
X1183607Y666831D01*
X1183733Y667512D01*
X1182629Y669119D01*
X1181948Y669245D01*
X1180843Y670852D01*
X1180969Y671534D01*
X1179865Y673141D01*
X1179183Y673267D01*
X1178079Y674874D01*
X1178205Y675555D01*
X1152435Y713048D01*
X1151810Y713164D01*
X1150705Y714771D01*
X1150821Y715396D01*
X1149717Y717003D01*
X1149091Y717119D01*
X1147986Y718726D01*
X1148102Y719352D01*
X1146998Y720959D01*
X1146372Y721075D01*
X1145267Y722682D01*
X1145383Y723308D01*
X1144279Y724915D01*
X1143653Y725031D01*
X1142548Y726638D01*
X1142664Y727264D01*
X1138690Y733046D01*
X1122675Y745919D01*
X1109116Y750247D01*
X1095209Y745806D01*
X1078231Y732148D01*
Y732147D01*
X1073338Y713600D01*
X1091340Y670778D01*
X1096306Y668007D01*
X1098768Y668015D01*
X1098773D01*
G03X1099518Y668207I-2J1551D01*
G03X1099868Y668470I-747J1358D01*
G01X1100266Y668868D01*
G03X1100452Y669443I-470J470D01*
G03X1100093Y669931I-658J-108D01*
G01X1097441Y671259D01*
G01X1525787Y82481D02*
Y84007D01*
G02X1526442Y84662I655J0D01*
G01X1527868D01*
G03X1529905Y86699I0J2037D01*
G01Y136203D01*
X1499464Y180149D01*
X1465442Y259694D01*
X1139542Y733837D01*
X1123229Y746950D01*
X1109116Y751455D01*
X1094655Y746837D01*
X1077215Y732807D01*
X1072126Y713515D01*
X1090433Y669967D01*
X1096009Y666855D01*
X1098772Y666865D01*
G03X1100072Y667198I1J2701D01*
G03X1100682Y667656I-1301J2367D01*
G01X1101489Y668463D01*
G02X1102041Y668743I706J-708D01*
G01X1102102Y668753D01*
G02X1102714Y668655I156J-988D01*
G01X1105315Y667322D01*
G01X1518701Y91930D02*
Y90404D01*
G03X1519356Y89749I655J0D01*
G01X1520814D01*
G03X1521669Y90604I0J855D01*
G01Y135134D01*
X1492578Y177156D01*
X1461066Y250861D01*
X1352826Y408374D01*
X1352145Y408500D01*
X1351040Y410107D01*
X1351167Y410788D01*
X1350062Y412396D01*
X1349381Y412522D01*
X1348277Y414129D01*
X1348403Y414810D01*
X1347298Y416417D01*
X1346617Y416544D01*
X1345513Y418151D01*
X1345639Y418832D01*
X1326109Y447253D01*
X1325483Y447369D01*
X1324379Y448977D01*
X1324495Y449602D01*
X1323391Y451209D01*
X1322765Y451325D01*
X1321661Y452933D01*
X1321777Y453558D01*
X1320672Y455165D01*
X1320046Y455281D01*
X1318942Y456889D01*
X1319058Y457514D01*
X1317954Y459121D01*
X1317328Y459237D01*
X1316224Y460845D01*
X1316340Y461470D01*
X1287321Y503699D01*
X1286695Y503815D01*
X1285590Y505422D01*
X1285707Y506048D01*
X1284602Y507655D01*
X1283976Y507771D01*
X1282872Y509378D01*
X1282988Y510004D01*
X1281884Y511611D01*
X1281258Y511727D01*
X1280154Y513334D01*
X1280270Y513960D01*
X1279165Y515567D01*
X1278539Y515683D01*
X1277435Y517290D01*
X1277551Y517916D01*
X1243201Y567903D01*
X1242575Y568019D01*
X1241470Y569626D01*
X1241587Y570252D01*
X1240482Y571859D01*
X1239856Y571975D01*
X1238752Y573582D01*
X1238868Y574208D01*
X1237764Y575815D01*
X1237138Y575931D01*
X1236034Y577538D01*
X1236150Y578164D01*
X1235045Y579771D01*
X1234419Y579887D01*
X1233315Y581494D01*
X1233431Y582120D01*
X1181400Y657837D01*
X1180719Y657963D01*
X1179615Y659570D01*
X1179741Y660252D01*
X1178637Y661859D01*
X1177955Y661985D01*
X1176851Y663592D01*
X1176977Y664274D01*
X1175873Y665881D01*
X1175192Y666007D01*
X1174087Y667614D01*
X1174213Y668295D01*
X1173109Y669903D01*
X1172428Y670029D01*
X1171323Y671636D01*
X1171450Y672317D01*
X1145364Y710278D01*
X1144738Y710394D01*
X1143634Y712002D01*
X1143750Y712627D01*
X1142645Y714234D01*
X1142020Y714350D01*
X1140915Y715958D01*
X1141031Y716583D01*
X1139927Y718190D01*
X1139301Y718306D01*
X1138197Y719914D01*
X1138313Y720539D01*
X1137208Y722146D01*
X1136583Y722262D01*
X1135478Y723870D01*
X1135594Y724495D01*
X1131242Y730829D01*
X1120705Y739300D01*
X1108161Y743301D01*
X1098018Y740062D01*
X1084008Y728794D01*
X1080321Y714815D01*
X1092483Y685888D01*
X1096305Y683755D01*
X1098768Y683763D01*
X1098773D01*
G03X1099518Y683955I-2J1551D01*
G03X1099868Y684218I-747J1358D01*
G01X1100266Y684616D01*
G03X1100452Y685191I-470J470D01*
G03X1100093Y685679I-658J-108D01*
G01X1097441Y687007D01*
G01X1511614Y87993D02*
Y86467D01*
G03X1512269Y85812I655J0D01*
G01X1513798D01*
G03X1514582Y86596I0J784D01*
G01Y134304D01*
X1487031Y174101D01*
X1456518Y245456D01*
X1318051Y446878D01*
X1317370Y447004D01*
X1316265Y448611D01*
X1316392Y449292D01*
X1315287Y450899D01*
X1314605Y451026D01*
X1313501Y452633D01*
X1313627Y453314D01*
X1312522Y454921D01*
X1311841Y455047D01*
X1310736Y456654D01*
X1310862Y457335D01*
X1281355Y500259D01*
X1280730Y500374D01*
X1279625Y501981D01*
X1279741Y502607D01*
X1278636Y504214D01*
X1278011Y504330D01*
X1276906Y505937D01*
X1277022Y506563D01*
X1275917Y508170D01*
X1275291Y508285D01*
X1274187Y509892D01*
X1274303Y510518D01*
X1273198Y512125D01*
X1272572Y512241D01*
X1271468Y513848D01*
X1271583Y514474D01*
X1237239Y564434D01*
X1236614Y564550D01*
X1235509Y566157D01*
X1235625Y566783D01*
X1234520Y568390D01*
X1233894Y568506D01*
X1232790Y570113D01*
X1232906Y570738D01*
X1231801Y572345D01*
X1231175Y572461D01*
X1230071Y574068D01*
X1230187Y574694D01*
X1229082Y576301D01*
X1228456Y576417D01*
X1227351Y578024D01*
X1227467Y578649D01*
X1206602Y609002D01*
X1205976Y609117D01*
X1204872Y610724D01*
X1204988Y611350D01*
X1203883Y612957D01*
X1203257Y613073D01*
X1202153Y614680D01*
X1202269Y615306D01*
X1201164Y616913D01*
X1200538Y617028D01*
X1199433Y618635D01*
X1199549Y619261D01*
X1198445Y620868D01*
X1197819Y620984D01*
X1196714Y622591D01*
X1196830Y623217D01*
X1175305Y654529D01*
X1174624Y654655D01*
X1173519Y656262D01*
X1173645Y656944D01*
X1172541Y658551D01*
X1171859Y658677D01*
X1170755Y660284D01*
X1170881Y660965D01*
X1169776Y662572D01*
X1169095Y662698D01*
X1167990Y664305D01*
X1168116Y664986D01*
X1167012Y666593D01*
X1166330Y666720D01*
X1165226Y668327D01*
X1165352Y669008D01*
X1139855Y706098D01*
X1139229Y706214D01*
X1138125Y707821D01*
X1138241Y708446D01*
X1137136Y710053D01*
X1136510Y710169D01*
X1135405Y711776D01*
X1135521Y712402D01*
X1134417Y714009D01*
X1133791Y714125D01*
X1132686Y715732D01*
X1132802Y716358D01*
X1131698Y717964D01*
X1131072Y718080D01*
X1129967Y719687D01*
X1130083Y720313D01*
X1125137Y727508D01*
X1117349Y733768D01*
X1108532Y736580D01*
X1101041Y734187D01*
X1090493Y725703D01*
X1087721Y715199D01*
X1093713Y700949D01*
X1096305Y699503D01*
X1098768Y699511D01*
X1098773D01*
G03X1099518Y699703I-2J1551D01*
G03X1099868Y699966I-747J1358D01*
G01X1100266Y700364D01*
G03X1100452Y700939I-470J470D01*
G03X1100093Y701427I-658J-108D01*
G01X1097441Y702755D01*
G01X1511614Y82481D02*
Y84007D01*
G02X1512269Y84662I655J0D01*
G01X1513798D01*
G03X1515732Y86596I0J1934D01*
G01Y134664D01*
X1488043Y174660D01*
X1457531Y246014D01*
X1125989Y728299D01*
X1117906Y734798D01*
X1108532Y737788D01*
X1100487Y735218D01*
X1089477Y726362D01*
X1089476D01*
X1086509Y715114D01*
X1092805Y700138D01*
X1096009Y698351D01*
X1098772Y698361D01*
G03X1100072Y698694I1J2701D01*
G03X1100682Y699152I-1301J2367D01*
G01X1101489Y699959D01*
G02X1102041Y700239I706J-708D01*
G01X1102102Y700249D01*
G02X1102714Y700151I156J-988D01*
G01X1105315Y698818D01*
G01X1398228Y87993D02*
Y86467D01*
G02X1397573Y85812I-655J0D01*
G01X1392485D01*
X1283636Y109943D01*
X1126539Y210024D01*
X1121367D01*
X1117430Y213961D01*
X1104269D01*
G03X1102074Y213052I0J-3104D01*
G01X1101267Y212245D01*
G02X1100715Y211965I-706J708D01*
G01X1100654Y211955D01*
G02X1100042Y212053I-156J988D01*
G01X1097441Y213386D01*
G01X1105315Y209449D02*
X1102663Y210777D01*
G02X1102304Y211265I299J596D01*
G02X1102490Y211840I656J105D01*
G01X1102888Y212238D01*
G02X1104271Y212811I1383J-1383D01*
G01X1116953D01*
X1120890Y208874D01*
X1126203D01*
X1134123Y203828D01*
X1134261Y203207D01*
X1135906Y202159D01*
X1136527Y202297D01*
X1138172Y201249D01*
X1138309Y200628D01*
X1139954Y199580D01*
X1140575Y199718D01*
X1142220Y198670D01*
X1142358Y198049D01*
X1144002Y197001D01*
X1144624Y197139D01*
X1146268Y196091D01*
X1146406Y195470D01*
X1148051Y194422D01*
X1148672Y194560D01*
X1283189Y108864D01*
X1392359Y84662D01*
X1397573D01*
G02X1398228Y84007I0J-655D01*
G01Y82481D01*
G01X1097441Y229134D02*
X1100042Y227801D01*
G03X1100654Y227703I456J890D01*
G01X1100715Y227713D01*
G03X1101267Y227993I-154J988D01*
G01X1102074Y228800D01*
G02X1104269Y229709I2195J-2195D01*
G01X1117430D01*
X1121367Y225772D01*
X1124722D01*
X1155547Y219607D01*
X1155648Y219581D01*
X1401011Y123670D01*
X1402347Y121888D01*
Y91236D01*
G03X1403834Y89749I1487J0D01*
G01X1404660D01*
G03X1405315Y90404I0J655D01*
G01Y91930D01*
G01X1105315Y225197D02*
X1102663Y226525D01*
G02X1102304Y227013I299J596D01*
G02X1102490Y227588I656J105D01*
G01X1102888Y227986D01*
G02X1104271Y228559I1383J-1383D01*
G01X1116953D01*
X1120890Y224622D01*
X1124608D01*
X1131123Y223319D01*
X1131476Y222789D01*
X1133388Y222407D01*
X1133918Y222760D01*
X1135830Y222377D01*
X1136183Y221848D01*
X1138095Y221465D01*
X1138625Y221818D01*
X1140537Y221436D01*
X1140890Y220906D01*
X1142802Y220524D01*
X1143331Y220877D01*
X1145243Y220494D01*
X1145596Y219965D01*
X1147509Y219582D01*
X1148038Y219935D01*
X1155294Y218484D01*
X1155298Y218483D01*
Y218481D01*
X1400287Y122718D01*
X1401197Y121504D01*
Y91236D01*
G03X1403834Y88599I2637J0D01*
G01X1404660D01*
G02X1405315Y87944I0J-655D01*
G01Y86418D01*
G01X1097441Y244882D02*
X1100042Y243549D01*
G03X1100654Y243451I456J890D01*
G01X1100715Y243461D01*
G03X1101267Y243741I-154J988D01*
G01X1102074Y244548D01*
G02X1104269Y245457I2195J-2195D01*
G01X1117430D01*
X1121367Y241520D01*
X1131881D01*
X1186167Y229982D01*
X1367119Y152485D01*
X1406020Y127701D01*
X1409434Y122328D01*
Y87299D01*
G03X1410921Y85812I1487J0D01*
G01X1411747D01*
G03X1412402Y86467I0J655D01*
G01Y87993D01*
G01X1105315Y240945D02*
X1102663Y242273D01*
G02X1102304Y242761I299J596D01*
G02X1102490Y243336I656J105D01*
G01X1102888Y243734D01*
G02X1104271Y244307I1383J-1383D01*
G01X1116953D01*
X1120890Y240370D01*
X1131760D01*
X1185817Y228880D01*
X1192183Y226154D01*
X1192440Y225511D01*
X1194233Y224743D01*
X1194876Y225000D01*
X1196668Y224233D01*
X1196926Y223589D01*
X1198718Y222822D01*
X1199362Y223079D01*
X1201154Y222311D01*
X1201412Y221668D01*
X1203204Y220900D01*
X1203848Y221158D01*
X1205640Y220390D01*
X1205898Y219747D01*
X1207690Y218979D01*
X1208334Y219237D01*
X1366580Y151464D01*
X1405186Y126868D01*
X1408284Y121993D01*
Y87299D01*
G03X1410921Y84662I2637J0D01*
G01X1411747D01*
G02X1412402Y84007I0J-655D01*
G01Y82481D01*
G01X1097441Y260630D02*
X1100042Y259297D01*
G03X1100654Y259199I456J890D01*
G01X1100715Y259209D01*
G03X1101267Y259489I-154J988D01*
G01X1102074Y260296D01*
G02X1104269Y261205I2195J-2195D01*
G01X1117430D01*
X1121367Y257268D01*
X1125316D01*
X1150917Y252060D01*
Y252059D01*
X1369752Y158342D01*
X1369974Y158201D01*
X1411156Y131977D01*
X1416520Y123557D01*
Y91236D01*
G03X1418007Y89749I1487J0D01*
G01X1418833D01*
G03X1419488Y90404I0J655D01*
G01Y91930D01*
G01X1105315Y256693D02*
X1102663Y258021D01*
G02X1102304Y258509I299J596D01*
G02X1102490Y259084I656J105D01*
G01X1102888Y259482D01*
G02X1104271Y260055I1383J-1383D01*
G01X1116953D01*
X1120890Y256118D01*
X1125200D01*
X1150564Y250958D01*
X1152357Y250190D01*
X1152614Y249547D01*
X1154407Y248779D01*
X1155050Y249037D01*
X1156842Y248269D01*
X1157100Y247626D01*
X1158893Y246858D01*
X1159536Y247116D01*
X1161328Y246348D01*
X1161586Y245705D01*
X1163379Y244937D01*
X1164022Y245195D01*
X1165814Y244427D01*
X1166072Y243784D01*
X1167864Y243016D01*
X1168508Y243274D01*
X1369211Y157322D01*
X1369212D01*
X1369357Y157230D01*
X1410323Y131144D01*
X1415370Y123221D01*
Y91236D01*
G03X1418007Y88599I2637J0D01*
G01X1418833D01*
G02X1419488Y87944I0J-655D01*
G01Y86418D01*
G01X1097441Y276378D02*
X1100042Y275045D01*
G03X1100654Y274947I456J890D01*
G01X1100715Y274957D01*
G03X1101267Y275237I-154J988D01*
G01X1102074Y276044D01*
G02X1104269Y276953I2195J-2195D01*
G01X1117430D01*
X1121367Y273016D01*
X1131259D01*
X1345615Y181217D01*
X1415692Y136631D01*
X1423607Y124208D01*
Y87299D01*
G03X1425094Y85812I1487J0D01*
G01X1425920D01*
G03X1426575Y86467I0J655D01*
G01Y87993D01*
G01X1105315Y272441D02*
X1102663Y273769D01*
G02X1102304Y274257I299J596D01*
G02X1102490Y274832I656J105D01*
G01X1102888Y275230D01*
G02X1104271Y275803I1383J-1383D01*
G01X1116953D01*
X1120890Y271866D01*
X1131023D01*
X1239492Y225412D01*
X1239749Y224769D01*
X1241542Y224001D01*
X1242185Y224259D01*
X1243977Y223491D01*
X1244235Y222848D01*
X1246028Y222080D01*
X1246671Y222338D01*
X1248463Y221570D01*
X1248721Y220927D01*
X1250514Y220159D01*
X1251157Y220417D01*
X1252949Y219649D01*
X1253207Y219006D01*
X1254999Y218238D01*
X1255643Y218496D01*
X1345076Y180196D01*
X1414859Y135797D01*
X1422457Y123872D01*
Y87299D01*
G03X1425094Y84662I2637J0D01*
G01X1425920D01*
G02X1426575Y84007I0J-655D01*
G01Y82481D01*
G01X1097441Y292126D02*
X1100042Y290793D01*
G03X1100654Y290695I456J890D01*
G01X1100715Y290705D01*
G03X1101267Y290985I-154J988D01*
G01X1102074Y291792D01*
G02X1104269Y292701I2195J-2195D01*
G01X1117444D01*
X1121381Y288764D01*
X1125451D01*
X1164350Y280850D01*
X1371833Y176184D01*
X1388294Y172534D01*
X1414635Y155754D01*
X1430693Y126888D01*
Y91236D01*
G03X1432180Y89749I1487J0D01*
G01X1433006D01*
G03X1433661Y90404I0J655D01*
G01Y91930D01*
G01X1105315Y288189D02*
X1102663Y289517D01*
G02X1102304Y290005I299J596D01*
G02X1102490Y290580I656J105D01*
G01X1102888Y290978D01*
G02X1104271Y291551I1383J-1383D01*
G01X1116967D01*
X1120904Y287614D01*
X1125335D01*
X1144183Y283779D01*
X1144565Y283201D01*
X1146476Y282812D01*
X1147054Y283195D01*
X1148965Y282806D01*
X1149347Y282228D01*
X1151258Y281839D01*
X1151836Y282222D01*
X1153747Y281833D01*
X1154129Y281255D01*
X1156040Y280866D01*
X1156618Y281249D01*
X1158529Y280860D01*
X1158911Y280282D01*
X1160822Y279893D01*
X1161400Y280276D01*
X1163969Y279753D01*
X1371444Y175092D01*
X1387847Y171455D01*
X1413771Y154940D01*
X1429543Y126589D01*
Y91236D01*
G03X1432180Y88599I2637J0D01*
G01X1433006D01*
G02X1433661Y87944I0J-655D01*
G01Y86418D01*
G01X1097441Y307874D02*
X1100042Y306541D01*
G03X1100654Y306443I456J890D01*
G01X1100715Y306453D01*
G03X1101267Y306733I-154J988D01*
G01X1102074Y307540D01*
G02X1104269Y308449I2195J-2195D01*
G01X1117430D01*
X1121367Y304512D01*
X1133947D01*
X1259874Y277744D01*
X1375398Y204152D01*
X1390697Y180137D01*
X1419476Y159943D01*
X1437780Y127043D01*
Y86567D01*
G03X1438535Y85812I755J0D01*
G01X1440093D01*
G03X1440748Y86467I0J655D01*
G01Y87993D01*
G01X1105315Y303937D02*
X1102663Y305265D01*
G02X1102304Y305753I299J596D01*
G02X1102490Y306328I656J105D01*
G01X1102888Y306726D01*
G02X1104271Y307299I1383J-1383D01*
G01X1116953D01*
X1120890Y303362D01*
X1133826D01*
X1259432Y276662D01*
X1352985Y217066D01*
X1353135Y216389D01*
X1354780Y215342D01*
X1355456Y215492D01*
X1357101Y214444D01*
X1357251Y213768D01*
X1358895Y212720D01*
X1359572Y212870D01*
X1361217Y211822D01*
X1361367Y211146D01*
X1363011Y210098D01*
X1363688Y210248D01*
X1365332Y209200D01*
X1365482Y208524D01*
X1367127Y207476D01*
X1367804Y207626D01*
X1374565Y203319D01*
X1389849Y179326D01*
X1418599Y159153D01*
X1436630Y126744D01*
Y86567D01*
G03X1438535Y84662I1905J0D01*
G01X1440093D01*
G02X1440748Y84007I0J-655D01*
G01Y82481D01*
G01X1097441Y323622D02*
X1100042Y322289D01*
G03X1100654Y322191I456J890D01*
G01X1100715Y322201D01*
G03X1101267Y322481I-154J988D01*
G01X1102074Y323288D01*
G02X1104269Y324197I2195J-2195D01*
G01X1117203D01*
X1121140Y320260D01*
X1127816D01*
X1133660Y316318D01*
X1245106Y294657D01*
X1380551Y208387D01*
X1396076Y184019D01*
X1424270Y164240D01*
X1444867Y131919D01*
Y90530D01*
G03X1445648Y89749I781J0D01*
G01X1447180D01*
G03X1447835Y90404I0J655D01*
G01Y91930D01*
G01X1105315Y319685D02*
X1102663Y321013D01*
G02X1102304Y321501I299J596D01*
G02X1102490Y322076I656J105D01*
G01X1102888Y322474D01*
G02X1104271Y323047I1383J-1383D01*
G01X1116726D01*
X1120663Y319110D01*
X1127464D01*
X1133210Y315233D01*
X1137061Y314485D01*
X1137417Y313957D01*
X1139331Y313585D01*
X1139859Y313941D01*
X1141773Y313569D01*
X1142129Y313041D01*
X1144043Y312669D01*
X1144570Y313025D01*
X1146485Y312653D01*
X1146840Y312125D01*
X1148755Y311753D01*
X1149282Y312109D01*
X1151196Y311737D01*
X1151552Y311210D01*
X1153466Y310837D01*
X1153994Y311193D01*
X1244672Y293569D01*
X1379718Y207554D01*
X1395228Y183208D01*
X1423422Y163429D01*
X1443717Y131583D01*
Y90530D01*
G03X1445648Y88599I1931J0D01*
G01X1447180D01*
G02X1447835Y87944I0J-655D01*
G01Y86418D01*
G54D37*
X135026Y997741D03*
X201726Y585741D03*
X754304Y864973D03*
X1776826Y1009741D03*
X1902159Y905750D03*
G54D19*
X103642Y36220D03*
X173228Y1062992D03*
X421653Y1141732D03*
X654822Y36220D03*
X670079Y1062992D03*
X1274311Y36220D03*
X1343701Y1062992D03*
X1592126Y1141732D03*
X1825492Y36220D03*
X1840551Y1062992D03*
G54D64*
X763818Y888398D03*
Y877398D03*
G54D55*
X727929Y882396D03*
X733835D03*
Y894608D03*
X727929D03*
G54D28*
X119741Y999116D03*
X151536Y997374D03*
X218236Y585374D03*
X186441Y587116D03*
X737984Y868796D03*
X852500Y487900D03*
X861900Y487800D03*
X1761541Y1011116D03*
X1793336Y1009374D03*
X1906500Y890200D03*
X1896943Y900950D03*
X1905943D03*
X1892500Y890700D03*
X1884500Y909200D03*
G54D46*
X450984Y124507D03*
X436811D03*
X479830D03*
X465157D03*
X550197D03*
X536023D03*
X521850D03*
X564370D03*
X1137446Y1024025D03*
Y1009852D03*
Y995679D03*
Y1038198D03*
Y1167343D03*
Y1224036D03*
Y1209863D03*
Y1195690D03*
Y1181516D03*
Y1266556D03*
Y1252383D03*
Y1238209D03*
Y1309076D03*
Y1323249D03*
Y1294902D03*
Y1280729D03*
Y1365769D03*
Y1351595D03*
Y1337422D03*
Y1394115D03*
Y1408288D03*
Y1379942D03*
X1447834Y124507D03*
X1504527D03*
X1490354D03*
X1518701D03*
X1532874D03*
G54D73*
X1039845Y1467746D03*
X1026345D03*
X1030845D03*
X1035345D03*
X1039845Y1463246D03*
X1026345D03*
X1030845D03*
X1035345D03*
X1005400Y1463157D03*
X1000900D03*
X996400D03*
X1009900D03*
X1005400Y1467657D03*
X1000900D03*
X996400D03*
X1009900D03*
X1035345Y1476746D03*
X1030845D03*
X1026345D03*
X1039845D03*
Y1472246D03*
X1026345D03*
X1030845D03*
X1035345D03*
X1005400Y1472157D03*
X1000900D03*
X996400D03*
X1009900D03*
Y1476657D03*
X1005400D03*
X1000900D03*
X996400D03*
X1023583Y1489593D03*
X995783D03*
X1000500Y1511400D03*
X1036578Y1511210D03*
X1014690Y1511178D03*
X1010190D03*
X1005690D03*
X1031790Y1511078D03*
X1027290D03*
X1019600Y1511100D03*
X1023583Y1501593D03*
Y1507593D03*
Y1495593D03*
X995783D03*
Y1501593D03*
Y1507593D03*
X1040583Y1517883D03*
X1031799Y1534392D03*
X1031882Y1528985D03*
X1026459Y1528919D03*
X1026376Y1534326D03*
X1014867D03*
X1014950Y1528919D03*
X1020290Y1534392D03*
X1020373Y1528985D03*
X1040500Y1529290D03*
X1040583Y1523883D03*
X1062700Y1463100D03*
X1058200D03*
X1067200D03*
X1062700Y1467600D03*
X1058200D03*
X1067200D03*
X1053700Y1463100D03*
Y1467600D03*
X1062700Y1472100D03*
X1058200D03*
X1067200D03*
Y1476600D03*
X1058200D03*
X1062700D03*
X1053700Y1472100D03*
Y1476600D03*
X1078683Y1489593D03*
X1051383D03*
X1041810Y1511084D03*
X1055310D03*
X1059810D03*
X1064310D03*
X1068810D03*
X1073310D03*
X1078683Y1495593D03*
Y1501593D03*
Y1507593D03*
Y1516593D03*
X1051383Y1495593D03*
Y1501593D03*
Y1507593D03*
X1078683Y1522593D03*
G54D83*
G01X658646Y515180D02*
X652926Y509460D01*
X569135D01*
X555264Y523331D01*
X553279D01*
G01X637213Y582155D02*
X616341D01*
X580456Y546270D01*
Y528308D01*
X572229Y520081D01*
G01X848325Y480275D02*
X844000Y475950D01*
Y467000D01*
X845400Y465600D01*
X851500D01*
X854445Y468545D01*
X856900D01*
G01X872000Y487750D02*
Y489700D01*
X853200Y508500D01*
X839500D01*
G01X863050Y458600D02*
Y454650D01*
X862000Y453600D01*
G01X851950Y458500D02*
Y454250D01*
X852000Y454200D01*
G01X863900Y463100D02*
X866100Y465300D01*
Y468545D01*
G01X863050Y458600D02*
Y462250D01*
X863900Y463100D01*
G01X861900Y484350D02*
Y469300D01*
X862655Y468545D01*
X866100D01*
G01X852500Y484450D02*
X848325Y480275D01*
G01X851950Y458500D02*
Y460650D01*
X856900Y465600D01*
Y468545D01*
G01X866100Y474455D02*
Y479900D01*
G01X870600Y476900D02*
X868155Y474455D01*
X866100D01*
G01Y484350D02*
Y479900D01*
G01X851800Y477200D02*
X854545Y474455D01*
X856900D01*
G01Y484450D02*
Y479950D01*
G01D02*
Y474455D01*
G01X866100Y472485D02*
X870185D01*
X872750Y475050D01*
X874900D01*
G01D02*
Y478000D01*
X873000Y479900D01*
G01X872000Y484250D02*
Y480900D01*
X873000Y479900D01*
G01X866100Y487850D02*
Y491600D01*
X864900Y492800D01*
X864100D01*
G01X861900Y487850D02*
Y492000D01*
X862700Y492800D01*
X864100D01*
G01X852500Y487950D02*
Y492000D01*
X853500Y493000D01*
X854600D01*
G01D02*
X855900D01*
X856900Y492000D01*
Y487950D01*
G01X911811Y1622441D02*
X916179D01*
X924300Y1614320D01*
Y1552491D01*
X927001Y1549790D01*
Y1520964D01*
X905991Y1499954D01*
Y1471943D01*
X867362Y1433314D01*
Y1341545D01*
X903539Y1305368D01*
G01X911811Y1618111D02*
X915749D01*
X921120Y1612740D01*
Y1551428D01*
X924001Y1548547D01*
Y1522208D01*
X902991Y1501198D01*
Y1473186D01*
X864444Y1434639D01*
Y1340220D01*
X920552Y1284112D01*
G01X911811Y1612599D02*
X914741D01*
X917880Y1609460D01*
Y1550425D01*
X921001Y1547304D01*
Y1523450D01*
X903505Y1505954D01*
X903504D01*
X899991Y1502441D01*
Y1474429D01*
X861444Y1435882D01*
Y1338977D01*
X941841Y1258580D01*
G01X911811Y1608268D02*
X913512D01*
X914740Y1607040D01*
Y1549322D01*
X915451Y1548611D01*
Y1522143D01*
X902262Y1508954D01*
X902261D01*
X896991Y1503684D01*
Y1475672D01*
X858444Y1437125D01*
Y1337734D01*
X966081Y1230097D01*
G01X886792Y1404100D02*
Y1389708D01*
X891800Y1384700D01*
Y1349965D01*
G01X896500Y1341800D02*
X891800Y1346500D01*
Y1349965D01*
G01X882226Y1404197D02*
X881375Y1403346D01*
Y1346409D01*
X891309Y1336475D01*
X983700D01*
X1010525Y1363300D01*
X1026100D01*
G01X873694Y1404575D02*
X878700Y1399569D01*
Y1347718D01*
X878699Y1347717D01*
Y1345301D01*
X890200Y1333800D01*
X984809D01*
X1010534Y1359525D01*
X1023700D01*
G01X1103064Y1113626D02*
Y1117564D01*
X1107758Y1122258D01*
Y1138259D01*
X1030079Y1215938D01*
Y1215939D01*
X1024809Y1221209D01*
X987698D01*
X903539Y1305368D01*
G01X1099020Y1112276D02*
Y1118020D01*
X1104137Y1123137D01*
Y1137637D01*
X1027079Y1214695D01*
Y1214696D01*
X1023567Y1218208D01*
X986456D01*
X920552Y1284112D01*
G01X1096460Y1115125D02*
Y1119460D01*
X1100765Y1123765D01*
Y1136766D01*
X1024079Y1213452D01*
Y1213453D01*
X1022323Y1215209D01*
X990184D01*
X990183Y1215208D01*
X985213D01*
X941841Y1258580D01*
G01X904725Y1622048D02*
Y1621325D01*
X901483Y1618083D01*
Y1583235D01*
X911516Y1573202D01*
G01X904725Y1616536D02*
X908570Y1612691D01*
Y1579848D01*
X911616Y1576802D01*
G01X904725Y1644882D02*
X908000Y1648157D01*
Y1651392D01*
X910408Y1653800D01*
X917959D01*
X924059Y1647700D01*
G01X1092742Y1113462D02*
Y1119242D01*
X1096394Y1122894D01*
Y1136894D01*
X1021079Y1212209D01*
X991427D01*
X991426Y1212208D01*
X983970D01*
X966081Y1230097D01*
G01X1037282Y995028D02*
Y1002114D01*
X1048429Y1013261D01*
X1065475D01*
G01X1115105Y1330335D02*
X1110531Y1334909D01*
X1082909D01*
X1054518Y1363300D01*
X1026100D01*
G01X1109593Y1330335D02*
X1107094Y1332834D01*
X1081200D01*
X1054509Y1359525D01*
X1023700D01*
G01X1041616Y997225D02*
X1050819Y1006428D01*
X1055881D01*
G01X1113530Y1009852D02*
X1110106Y1006428D01*
X1055881D01*
G01X1119042Y1009852D02*
X1115633Y1013261D01*
X1065475D01*
G01X1395300Y438500D02*
X1568500D01*
G01X1502400Y544100D02*
X1548021D01*
G01D02*
X1568500D01*
G01X1768692Y966073D02*
X1760759Y958140D01*
X1733168D01*
X1729908Y961400D01*
X1694800D01*
X1685047Y971153D01*
Y1014966D01*
G54D65*
X872366Y406550D03*
X861398D03*
X1066784Y404700D03*
X1055816D03*
G54D56*
X729898Y882446D03*
X731866D03*
Y894558D03*
X729898D03*
G54D29*
X119741Y995716D03*
X151536Y993974D03*
X218236Y581974D03*
X186441Y583716D03*
X737984Y865396D03*
X852500Y484500D03*
X861900Y484400D03*
X1761541Y1007716D03*
X1793336Y1005974D03*
X1892500Y887300D03*
X1906500Y886800D03*
X1896943Y897550D03*
X1905943D03*
X1884500Y905800D03*
G54D47*
X694613Y593113D03*
Y621397D03*
G54D74*
X1358858Y596400D03*
X1387142D03*
G54D38*
X140626Y997741D03*
X207326Y585741D03*
X759904Y864973D03*
X1782426Y1009741D03*
X1907759Y905750D03*
G54D48*
X711711Y881500D03*
X743200Y874600D03*
X729182Y862502D03*
X874900Y471600D03*
X872000Y484300D03*
X856900Y484500D03*
X866100Y484400D03*
X1888000Y887300D03*
X1889500Y905800D03*
X1892443Y897550D03*
G54D66*
X854849Y423076D03*
X879649D03*
X1041380Y421129D03*
X1066180D03*
X1841693Y839032D03*
X1905593D03*
X1880793D03*
X1866493D03*
G54D75*
X1857176Y858948D03*
Y893570D03*
G54D39*
X125263Y1001725D03*
X191963Y589725D03*
X1767063Y1013725D03*
X1847200Y904000D03*
X1864700Y936500D03*
G54D57*
X722319Y865905D03*
X1887626Y917859D03*
G54D76*
X1868276Y916059D03*
G54D58*
X719819Y865905D03*
X1885126Y917859D03*
G54D67*
X874800Y467500D03*
X850100Y473300D03*
X1436200Y561900D03*
X1893500Y909300D03*
G54D49*
X711711Y884900D03*
X743200Y878000D03*
X729182Y865902D03*
X874900Y475000D03*
X872000Y487700D03*
X856900Y487900D03*
X866100Y487800D03*
X1889500Y909200D03*
X1892443Y900950D03*
X1888000Y890700D03*
G54D77*
X1860402Y925702D03*
X1858433D03*
Y906416D03*
X1860402D03*
X1878119Y925702D03*
X1876150D03*
X1874182D03*
X1872213D03*
X1870245D03*
X1868276D03*
X1866307D03*
X1864339D03*
X1862370D03*
Y906416D03*
X1864339D03*
X1866307D03*
X1868276D03*
X1870245D03*
X1872213D03*
X1874182D03*
X1876150D03*
X1878119D03*
G54D68*
X874800Y463900D03*
X850100Y469700D03*
X1436200Y558300D03*
X1893500Y905700D03*
G54D59*
X719119Y858953D03*
X1898000Y888500D03*
G54D78*
G01X95363Y987725D02*
X97863Y985225D01*
X99563D01*
X101063Y983725D01*
X102148D01*
X102736Y983137D01*
X106157D01*
G01X162063Y575725D02*
X164563Y573225D01*
X166263D01*
X167763Y571725D01*
X168848D01*
X169436Y571137D01*
X172857D01*
G01X130463Y983925D02*
X129675Y983137D01*
X125443D01*
G01X197163Y571925D02*
X196375Y571137D01*
X192143D01*
G01X856900Y470515D02*
X853115D01*
X852350Y469750D01*
X850100D01*
G01X856900Y472485D02*
X853165D01*
X852400Y473250D01*
X850100D01*
G01X874800Y467450D02*
X873550D01*
X870485Y470515D01*
X866100D01*
G01X1735481Y1008554D02*
X1740210Y1003825D01*
Y997844D01*
X1742917Y995137D01*
X1747957D01*
G01X1772263Y995925D02*
X1771475Y995137D01*
X1767243D01*
G01X1873001Y901396D02*
X1872213Y902184D01*
Y906416D01*
G01Y925702D02*
Y929123D01*
X1876047Y932957D01*
X1877762D01*
X1882801Y937996D01*
G54D69*
X866100Y468545D03*
Y470515D03*
Y472485D03*
Y474455D03*
X856900D03*
Y472485D03*
Y470515D03*
Y468545D03*
G54D79*
G01X718969Y865905D02*
X718547D01*
X716233Y868219D01*
M02*
